G04 ================== begin FILE IDENTIFICATION RECORD ==================*
G04 Layout Name:  D:/<user>/Wistron_project/16318-2/gbr/16318-2.brd*
G04 Film Name:    L1*
G04 File Format:  Gerber RS274X*
G04 File Origin:  Cadence Allegro 16.5-S056*
G04 Origin Date:  Mon Aug 07 11:09:35 2017*
G04 *
G04 Layer:  VIA CLASS/TOP*
G04 Layer:  PIN/TOP*
G04 Layer:  ETCH/TOP*
G04 Layer:  DRAWING FORMAT/LAYER_PCB_STORY*
G04 Layer:  DRAWING FORMAT/LAYER_L1*
G04 *
G04 Offset:    (0.00 0.00)*
G04 Mirror:    No*
G04 Mode:      Positive*
G04 Rotation:  0*
G04 FullContactRelief:  No*
G04 UndefLineWidth:     6.00*
G04 ================== end FILE IDENTIFICATION RECORD ====================*
%FSLAX35Y35*MOIN*%
%IR0*IPPOS*OFA0.00000B0.00000*MIA0B0*SFA1.00000B1.00000*%
%AMMACRO56*
4,1,40,.013,.017,
-.013,.017,
-.013695,.016939,
-.014368,.016759,
-.015,.016464,
-.015571,.016064,
-.016064,.015571,
-.016464,.015,
-.016759,.014368,
-.016939,.013695,
-.017,.013,
-.017,-.013,
-.016939,-.013695,
-.016759,-.014368,
-.016464,-.015,
-.016064,-.015571,
-.015571,-.016064,
-.015,-.016464,
-.014368,-.016759,
-.013695,-.016939,
-.013,-.017,
.013,-.017,
.013695,-.016939,
.014368,-.016759,
.015,-.016464,
.015571,-.016064,
.016064,-.015571,
.016464,-.015,
.016759,-.014368,
.016939,-.013695,
.017,-.013,
.017,.013,
.016939,.013695,
.016759,.014368,
.016464,.015,
.016064,.015571,
.015571,.016064,
.015,.016464,
.014368,.016759,
.013695,.016939,
.013,.017,
0.0*
%
%ADD56MACRO56*%
%AMMACRO17*
4,1,40,.017,-.013,
.017,.013,
.016939,.013695,
.016759,.014368,
.016464,.015,
.016064,.015571,
.015571,.016064,
.015,.016464,
.014368,.016759,
.013695,.016939,
.013,.017,
-.013,.017,
-.013695,.016939,
-.014368,.016759,
-.015,.016464,
-.015571,.016064,
-.016064,.015571,
-.016464,.015,
-.016759,.014368,
-.016939,.013695,
-.017,.013,
-.017,-.013,
-.016939,-.013695,
-.016759,-.014368,
-.016464,-.015,
-.016064,-.015571,
-.015571,-.016064,
-.015,-.016464,
-.014368,-.016759,
-.013695,-.016939,
-.013,-.017,
.013,-.017,
.013695,-.016939,
.014368,-.016759,
.015,-.016464,
.015571,-.016064,
.016064,-.015571,
.016464,-.015,
.016759,-.014368,
.016939,-.013695,
.017,-.013,
0.0*
%
%ADD17MACRO17*%
%AMMACRO82*
4,1,40,.008,.009,
.008695,.008939,
.009368,.008759,
.01,.008464,
.010571,.008064,
.011064,.007571,
.011464,.007,
.011759,.006368,
.011939,.005695,
.012,.005,
.012,-.005,
.011939,-.005695,
.011759,-.006368,
.011464,-.007,
.011064,-.007571,
.010571,-.008064,
.01,-.008464,
.009368,-.008759,
.008695,-.008939,
.008,-.009,
-.008,-.009,
-.008695,-.008939,
-.009368,-.008759,
-.01,-.008464,
-.010571,-.008064,
-.011064,-.007571,
-.011464,-.007,
-.011759,-.006368,
-.011939,-.005695,
-.012,-.005,
-.012,.005,
-.011939,.005695,
-.011759,.006368,
-.011464,.007,
-.011064,.007571,
-.010571,.008064,
-.01,.008464,
-.009368,.008759,
-.008695,.008939,
-.008,.009,
.008,.009,
0.0*
%
%ADD82MACRO82*%
%AMMACRO108*
4,1,40,.019,.017,
-.019,.017,
-.019695,.016939,
-.020368,.016759,
-.021,.016464,
-.021571,.016064,
-.022064,.015571,
-.022464,.015,
-.022759,.014368,
-.022939,.013695,
-.023,.013,
-.023,-.013,
-.022939,-.013695,
-.022759,-.014368,
-.022464,-.015,
-.022064,-.015571,
-.021571,-.016064,
-.021,-.016464,
-.020368,-.016759,
-.019695,-.016939,
-.019,-.017,
.019,-.017,
.019695,-.016939,
.020368,-.016759,
.021,-.016464,
.021571,-.016064,
.022064,-.015571,
.022464,-.015,
.022759,-.014368,
.022939,-.013695,
.023,-.013,
.023,.013,
.022939,.013695,
.022759,.014368,
.022464,.015,
.022064,.015571,
.021571,.016064,
.021,.016464,
.020368,.016759,
.019695,.016939,
.019,.017,
0.0*
%
%ADD108MACRO108*%
%ADD69O,.06X.111*%
%AMMACRO65*
4,1,15,-.0275,-.115,
-.0275,.02323,
-.02431,.026923,
-.021809,.031114,
-.020074,.035675,
-.019157,.040469,
-.019087,.045348,
-.019865,.050166,
-.021468,.054776,
-.023847,.059037,
-.02693,.06282,
-.0275,.06339,
-.0275,.115,
.0275,.115,
.0275,-.115,
-.0275,-.115,
0.0*
%
%ADD65MACRO65*%
%ADD133R,.01X.007*%
%ADD119R,.007X.01*%
%ADD18C,.01*%
%ADD21C,.02*%
%ADD136R,.147X.014*%
%ADD103C,.03*%
%ADD45C,.04*%
%ADD40C,.022*%
%AMMACRO140*
4,1,40,-.007,.004,
-.007,-.004,
-.00697,-.004347,
-.006879,-.004684,
-.006732,-.005,
-.006532,-.005286,
-.006286,-.005532,
-.006,-.005732,
-.005684,-.005879,
-.005347,-.00597,
-.005,-.006,
.005,-.006,
.005347,-.00597,
.005684,-.005879,
.006,-.005732,
.006286,-.005532,
.006532,-.005286,
.006732,-.005,
.006879,-.004684,
.00697,-.004347,
.007,-.004,
.007,.004,
.00697,.004347,
.006879,.004684,
.006732,.005,
.006532,.005286,
.006286,.005532,
.006,.005732,
.005684,.005879,
.005347,.00597,
.005,.006,
-.005,.006,
-.005347,.00597,
-.005684,.005879,
-.006,.005732,
-.006286,.005532,
-.006532,.005286,
-.006732,.005,
-.006879,.004684,
-.00697,.004347,
-.007,.004,
0.0*
%
%ADD140MACRO140*%
%ADD111C,.05*%
%ADD28C,.014*%
%ADD77C,.042*%
%ADD50C,.016*%
%ADD29C,.026*%
%ADD116C,.036*%
%ADD51C,.018*%
%ADD10C,.028*%
%ADD115C,.029*%
%ADD11C,.056*%
%AMMACRO63*
4,1,40,.0225,-.007,
.022378,-.008389,
.022018,-.009736,
.021428,-.011,
.020628,-.012142,
.019642,-.013128,
.0185,-.013928,
.017236,-.014518,
.015889,-.014878,
.0145,-.015,
-.0145,-.015,
-.015889,-.014878,
-.017236,-.014518,
-.0185,-.013928,
-.019642,-.013128,
-.020628,-.012142,
-.021428,-.011,
-.022018,-.009736,
-.022378,-.008389,
-.0225,-.007,
-.0225,.007,
-.022378,.008389,
-.022018,.009736,
-.021428,.011,
-.020628,.012142,
-.019642,.013128,
-.0185,.013928,
-.017236,.014518,
-.015889,.014878,
-.0145,.015,
.0145,.015,
.015889,.014878,
.017236,.014518,
.0185,.013928,
.019642,.013128,
.020628,.012142,
.021428,.011,
.022018,.009736,
.022378,.008389,
.0225,.007,
.0225,-.007,
0.0*
%
%ADD63MACRO63*%
%AMMACRO75*
4,1,40,-.007,-.0225,
-.008389,-.022378,
-.009736,-.022018,
-.011,-.021428,
-.012142,-.020628,
-.013128,-.019642,
-.013928,-.0185,
-.014518,-.017236,
-.014878,-.015889,
-.015,-.0145,
-.015,.0145,
-.014878,.015889,
-.014518,.017236,
-.013928,.0185,
-.013128,.019642,
-.012142,.020628,
-.011,.021428,
-.009736,.022018,
-.008389,.022378,
-.007,.0225,
.007,.0225,
.008389,.022378,
.009736,.022018,
.011,.021428,
.012142,.020628,
.013128,.019642,
.013928,.0185,
.014518,.017236,
.014878,.015889,
.015,.0145,
.015,-.0145,
.014878,-.015889,
.014518,-.017236,
.013928,-.0185,
.013128,-.019642,
.012142,-.020628,
.011,-.021428,
.009736,-.022018,
.008389,-.022378,
.007,-.0225,
-.007,-.0225,
0.0*
%
%ADD75MACRO75*%
%AMMACRO26*
4,1,40,.007,.011,
-.007,.011,
-.007695,.010939,
-.008368,.010759,
-.009,.010464,
-.009571,.010064,
-.010064,.009571,
-.010464,.009,
-.010759,.008368,
-.010939,.007695,
-.011,.007,
-.011,-.007,
-.010939,-.007695,
-.010759,-.008368,
-.010464,-.009,
-.010064,-.009571,
-.009571,-.010064,
-.009,-.010464,
-.008368,-.010759,
-.007695,-.010939,
-.007,-.011,
.007,-.011,
.007695,-.010939,
.008368,-.010759,
.009,-.010464,
.009571,-.010064,
.010064,-.009571,
.010464,-.009,
.010759,-.008368,
.010939,-.007695,
.011,-.007,
.011,.007,
.010939,.007695,
.010759,.008368,
.010464,.009,
.010064,.009571,
.009571,.010064,
.009,.010464,
.008368,.010759,
.007695,.010939,
.007,.011,
0.0*
%
%ADD26MACRO26*%
%AMMACRO14*
4,1,40,.011,-.007,
.011,.007,
.010939,.007695,
.010759,.008368,
.010464,.009,
.010064,.009571,
.009571,.010064,
.009,.010464,
.008368,.010759,
.007695,.010939,
.007,.011,
-.007,.011,
-.007695,.010939,
-.008368,.010759,
-.009,.010464,
-.009571,.010064,
-.010064,.009571,
-.010464,.009,
-.010759,.008368,
-.010939,.007695,
-.011,.007,
-.011,-.007,
-.010939,-.007695,
-.010759,-.008368,
-.010464,-.009,
-.010064,-.009571,
-.009571,-.010064,
-.009,-.010464,
-.008368,-.010759,
-.007695,-.010939,
-.007,-.011,
.007,-.011,
.007695,-.010939,
.008368,-.010759,
.009,-.010464,
.009571,-.010064,
.010064,-.009571,
.010464,-.009,
.010759,-.008368,
.010939,-.007695,
.011,-.007,
0.0*
%
%ADD14MACRO14*%
%ADD123R,.066X.066*%
%AMMACRO35*
4,1,40,-.012,.008,
-.012,-.008,
-.011939,-.008695,
-.011759,-.009368,
-.011464,-.01,
-.011064,-.010571,
-.010571,-.011064,
-.01,-.011464,
-.009368,-.011759,
-.008695,-.011939,
-.008,-.012,
.008,-.012,
.008695,-.011939,
.009368,-.011759,
.01,-.011464,
.010571,-.011064,
.011064,-.010571,
.011464,-.01,
.011759,-.009368,
.011939,-.008695,
.012,-.008,
.012,.008,
.011939,.008695,
.011759,.009368,
.011464,.01,
.011064,.010571,
.010571,.011064,
.01,.011464,
.009368,.011759,
.008695,.011939,
.008,.012,
-.008,.012,
-.008695,.011939,
-.009368,.011759,
-.01,.011464,
-.010571,.011064,
-.011064,.010571,
-.011464,.01,
-.011759,.009368,
-.011939,.008695,
-.012,.008,
0.0*
%
%ADD35MACRO35*%
%AMMACRO37*
4,1,40,.008,.012,
-.008,.012,
-.008695,.011939,
-.009368,.011759,
-.01,.011464,
-.010571,.011064,
-.011064,.010571,
-.011464,.01,
-.011759,.009368,
-.011939,.008695,
-.012,.008,
-.012,-.008,
-.011939,-.008695,
-.011759,-.009368,
-.011464,-.01,
-.011064,-.010571,
-.010571,-.011064,
-.01,-.011464,
-.009368,-.011759,
-.008695,-.011939,
-.008,-.012,
.008,-.012,
.008695,-.011939,
.009368,-.011759,
.01,-.011464,
.010571,-.011064,
.011064,-.010571,
.011464,-.01,
.011759,-.009368,
.011939,-.008695,
.012,-.008,
.012,.008,
.011939,.008695,
.011759,.009368,
.011464,.01,
.011064,.010571,
.010571,.011064,
.01,.011464,
.009368,.011759,
.008695,.011939,
.008,.012,
0.0*
%
%ADD37MACRO37*%
%AMMACRO84*
4,1,40,-.013,-.017,
.013,-.017,
.013695,-.016939,
.014368,-.016759,
.015,-.016464,
.015571,-.016064,
.016064,-.015571,
.016464,-.015,
.016759,-.014368,
.016939,-.013695,
.017,-.013,
.017,.013,
.016939,.013695,
.016759,.014368,
.016464,.015,
.016064,.015571,
.015571,.016064,
.015,.016464,
.014368,.016759,
.013695,.016939,
.013,.017,
-.013,.017,
-.013695,.016939,
-.014368,.016759,
-.015,.016464,
-.015571,.016064,
-.016064,.015571,
-.016464,.015,
-.016759,.014368,
-.016939,.013695,
-.017,.013,
-.017,-.013,
-.016939,-.013695,
-.016759,-.014368,
-.016464,-.015,
-.016064,-.015571,
-.015571,-.016064,
-.015,-.016464,
-.014368,-.016759,
-.013695,-.016939,
-.013,-.017,
0.0*
%
%ADD84MACRO84*%
%AMMACRO90*
4,1,40,-.017,.013,
-.017,-.013,
-.016939,-.013695,
-.016759,-.014368,
-.016464,-.015,
-.016064,-.015571,
-.015571,-.016064,
-.015,-.016464,
-.014368,-.016759,
-.013695,-.016939,
-.013,-.017,
.013,-.017,
.013695,-.016939,
.014368,-.016759,
.015,-.016464,
.015571,-.016064,
.016064,-.015571,
.016464,-.015,
.016759,-.014368,
.016939,-.013695,
.017,-.013,
.017,.013,
.016939,.013695,
.016759,.014368,
.016464,.015,
.016064,.015571,
.015571,.016064,
.015,.016464,
.014368,.016759,
.013695,.016939,
.013,.017,
-.013,.017,
-.013695,.016939,
-.014368,.016759,
-.015,.016464,
-.015571,.016064,
-.016064,.015571,
-.016464,.015,
-.016759,.014368,
-.016939,.013695,
-.017,.013,
0.0*
%
%ADD90MACRO90*%
%AMMACRO80*
4,1,40,-.009,.008,
-.008939,.008695,
-.008759,.009368,
-.008464,.01,
-.008064,.010571,
-.007571,.011064,
-.007,.011464,
-.006368,.011759,
-.005695,.011939,
-.005,.012,
.005,.012,
.005695,.011939,
.006368,.011759,
.007,.011464,
.007571,.011064,
.008064,.010571,
.008464,.01,
.008759,.009368,
.008939,.008695,
.009,.008,
.009,-.008,
.008939,-.008695,
.008759,-.009368,
.008464,-.01,
.008064,-.010571,
.007571,-.011064,
.007,-.011464,
.006368,-.011759,
.005695,-.011939,
.005,-.012,
-.005,-.012,
-.005695,-.011939,
-.006368,-.011759,
-.007,-.011464,
-.007571,-.011064,
-.008064,-.010571,
-.008464,-.01,
-.008759,-.009368,
-.008939,-.008695,
-.009,-.008,
-.009,.008,
0.0*
%
%ADD80MACRO80*%
%AMMACRO121*
4,1,6,-.0135,.005,
-.0065,.005,
.0135,.025,
.0135,-.025,
-.0065,-.005,
-.0135,-.005,
-.0135,.005,
0.0*
%
%ADD121MACRO121*%
%AMMACRO81*
4,1,40,.008,.009,
.008695,.008939,
.009368,.008759,
.01,.008464,
.010571,.008064,
.011064,.007571,
.011464,.007,
.011759,.006368,
.011939,.005695,
.012,.005,
.012,-.005,
.011939,-.005695,
.011759,-.006368,
.011464,-.007,
.011064,-.007571,
.010571,-.008064,
.01,-.008464,
.009368,-.008759,
.008695,-.008939,
.008,-.009,
-.008,-.009,
-.008695,-.008939,
-.009368,-.008759,
-.01,-.008464,
-.010571,-.008064,
-.011064,-.007571,
-.011464,-.007,
-.011759,-.006368,
-.011939,-.005695,
-.012,-.005,
-.012,.005,
-.011939,.005695,
-.011759,.006368,
-.011464,.007,
-.011064,.007571,
-.010571,.008064,
-.01,.008464,
-.009368,.008759,
-.008695,.008939,
-.008,.009,
.008,.009,
0.0*
%
%ADD81MACRO81*%
%AMMACRO46*
4,1,6,.005,.0135,
.005,.0065,
.025,-.0135,
-.025,-.0135,
-.005,.0065,
-.005,.0135,
.005,.0135,
0.0*
%
%ADD46MACRO46*%
%AMMACRO130*
4,1,20,-.1095,-.0655,
-.1095,-.051,
-.12,-.051,
-.12,-.0375,
-.1095,-.0375,
-.1095,.0375,
-.12,.0375,
-.12,.051,
-.1095,.051,
-.1095,.0655,
.1095,.0655,
.1095,.051,
.12,.051,
.12,.0375,
.1095,.0375,
.1095,-.0375,
.12,-.0375,
.12,-.051,
.1095,-.051,
.1095,-.0655,
-.1095,-.0655,
0.0*
%
%ADD130MACRO130*%
%AMMACRO27*
4,1,40,.007,.011,
-.007,.011,
-.007695,.010939,
-.008368,.010759,
-.009,.010464,
-.009571,.010064,
-.010064,.009571,
-.010464,.009,
-.010759,.008368,
-.010939,.007695,
-.011,.007,
-.011,-.007,
-.010939,-.007695,
-.010759,-.008368,
-.010464,-.009,
-.010064,-.009571,
-.009571,-.010064,
-.009,-.010464,
-.008368,-.010759,
-.007695,-.010939,
-.007,-.011,
.007,-.011,
.007695,-.010939,
.008368,-.010759,
.009,-.010464,
.009571,-.010064,
.010064,-.009571,
.010464,-.009,
.010759,-.008368,
.010939,-.007695,
.011,-.007,
.011,.007,
.010939,.007695,
.010759,.008368,
.010464,.009,
.010064,.009571,
.009571,.010064,
.009,.010464,
.008368,.010759,
.007695,.010939,
.007,.011,
0.0*
%
%ADD27MACRO27*%
%AMMACRO15*
4,1,40,.011,-.007,
.011,.007,
.010939,.007695,
.010759,.008368,
.010464,.009,
.010064,.009571,
.009571,.010064,
.009,.010464,
.008368,.010759,
.007695,.010939,
.007,.011,
-.007,.011,
-.007695,.010939,
-.008368,.010759,
-.009,.010464,
-.009571,.010064,
-.010064,.009571,
-.010464,.009,
-.010759,.008368,
-.010939,.007695,
-.011,.007,
-.011,-.007,
-.010939,-.007695,
-.010759,-.008368,
-.010464,-.009,
-.010064,-.009571,
-.009571,-.010064,
-.009,-.010464,
-.008368,-.010759,
-.007695,-.010939,
-.007,-.011,
.007,-.011,
.007695,-.010939,
.008368,-.010759,
.009,-.010464,
.009571,-.010064,
.010064,-.009571,
.010464,-.009,
.010759,-.008368,
.010939,-.007695,
.011,-.007,
0.0*
%
%ADD15MACRO15*%
%AMMACRO34*
4,1,40,-.012,.008,
-.012,-.008,
-.011939,-.008695,
-.011759,-.009368,
-.011464,-.01,
-.011064,-.010571,
-.010571,-.011064,
-.01,-.011464,
-.009368,-.011759,
-.008695,-.011939,
-.008,-.012,
.008,-.012,
.008695,-.011939,
.009368,-.011759,
.01,-.011464,
.010571,-.011064,
.011064,-.010571,
.011464,-.01,
.011759,-.009368,
.011939,-.008695,
.012,-.008,
.012,.008,
.011939,.008695,
.011759,.009368,
.011464,.01,
.011064,.010571,
.010571,.011064,
.01,.011464,
.009368,.011759,
.008695,.011939,
.008,.012,
-.008,.012,
-.008695,.011939,
-.009368,.011759,
-.01,.011464,
-.010571,.011064,
-.011064,.010571,
-.011464,.01,
-.011759,.009368,
-.011939,.008695,
-.012,.008,
0.0*
%
%ADD34MACRO34*%
%AMMACRO36*
4,1,40,.008,.012,
-.008,.012,
-.008695,.011939,
-.009368,.011759,
-.01,.011464,
-.010571,.011064,
-.011064,.010571,
-.011464,.01,
-.011759,.009368,
-.011939,.008695,
-.012,.008,
-.012,-.008,
-.011939,-.008695,
-.011759,-.009368,
-.011464,-.01,
-.011064,-.010571,
-.010571,-.011064,
-.01,-.011464,
-.009368,-.011759,
-.008695,-.011939,
-.008,-.012,
.008,-.012,
.008695,-.011939,
.009368,-.011759,
.01,-.011464,
.010571,-.011064,
.011064,-.010571,
.011464,-.01,
.011759,-.009368,
.011939,-.008695,
.012,-.008,
.012,.008,
.011939,.008695,
.011759,.009368,
.011464,.01,
.011064,.010571,
.010571,.011064,
.01,.011464,
.009368,.011759,
.008695,.011939,
.008,.012,
0.0*
%
%ADD36MACRO36*%
%AMMACRO85*
4,1,40,-.013,-.017,
.013,-.017,
.013695,-.016939,
.014368,-.016759,
.015,-.016464,
.015571,-.016064,
.016064,-.015571,
.016464,-.015,
.016759,-.014368,
.016939,-.013695,
.017,-.013,
.017,.013,
.016939,.013695,
.016759,.014368,
.016464,.015,
.016064,.015571,
.015571,.016064,
.015,.016464,
.014368,.016759,
.013695,.016939,
.013,.017,
-.013,.017,
-.013695,.016939,
-.014368,.016759,
-.015,.016464,
-.015571,.016064,
-.016064,.015571,
-.016464,.015,
-.016759,.014368,
-.016939,.013695,
-.017,.013,
-.017,-.013,
-.016939,-.013695,
-.016759,-.014368,
-.016464,-.015,
-.016064,-.015571,
-.015571,-.016064,
-.015,-.016464,
-.014368,-.016759,
-.013695,-.016939,
-.013,-.017,
0.0*
%
%ADD85MACRO85*%
%AMMACRO91*
4,1,40,-.017,.013,
-.017,-.013,
-.016939,-.013695,
-.016759,-.014368,
-.016464,-.015,
-.016064,-.015571,
-.015571,-.016064,
-.015,-.016464,
-.014368,-.016759,
-.013695,-.016939,
-.013,-.017,
.013,-.017,
.013695,-.016939,
.014368,-.016759,
.015,-.016464,
.015571,-.016064,
.016064,-.015571,
.016464,-.015,
.016759,-.014368,
.016939,-.013695,
.017,-.013,
.017,.013,
.016939,.013695,
.016759,.014368,
.016464,.015,
.016064,.015571,
.015571,.016064,
.015,.016464,
.014368,.016759,
.013695,.016939,
.013,.017,
-.013,.017,
-.013695,.016939,
-.014368,.016759,
-.015,.016464,
-.015571,.016064,
-.016064,.015571,
-.016464,.015,
-.016759,.014368,
-.016939,.013695,
-.017,.013,
0.0*
%
%ADD91MACRO91*%
%AMMACRO79*
4,1,40,.009,-.008,
.008939,-.008695,
.008759,-.009368,
.008464,-.01,
.008064,-.010571,
.007571,-.011064,
.007,-.011464,
.006368,-.011759,
.005695,-.011939,
.005,-.012,
-.005,-.012,
-.005695,-.011939,
-.006368,-.011759,
-.007,-.011464,
-.007571,-.011064,
-.008064,-.010571,
-.008464,-.01,
-.008759,-.009368,
-.008939,-.008695,
-.009,-.008,
-.009,.008,
-.008939,.008695,
-.008759,.009368,
-.008464,.01,
-.008064,.010571,
-.007571,.011064,
-.007,.011464,
-.006368,.011759,
-.005695,.011939,
-.005,.012,
.005,.012,
.005695,.011939,
.006368,.011759,
.007,.011464,
.007571,.011064,
.008064,.010571,
.008464,.01,
.008759,.009368,
.008939,.008695,
.009,.008,
.009,-.008,
0.0*
%
%ADD79MACRO79*%
%AMMACRO87*
4,1,40,-.008,-.009,
-.008695,-.008939,
-.009368,-.008759,
-.01,-.008464,
-.010571,-.008064,
-.011064,-.007571,
-.011464,-.007,
-.011759,-.006368,
-.011939,-.005695,
-.012,-.005,
-.012,.005,
-.011939,.005695,
-.011759,.006368,
-.011464,.007,
-.011064,.007571,
-.010571,.008064,
-.01,.008464,
-.009368,.008759,
-.008695,.008939,
-.008,.009,
.008,.009,
.008695,.008939,
.009368,.008759,
.01,.008464,
.010571,.008064,
.011064,.007571,
.011464,.007,
.011759,.006368,
.011939,.005695,
.012,.005,
.012,-.005,
.011939,-.005695,
.011759,-.006368,
.011464,-.007,
.011064,-.007571,
.010571,-.008064,
.01,-.008464,
.009368,-.008759,
.008695,-.008939,
.008,-.009,
-.008,-.009,
0.0*
%
%ADD87MACRO87*%
%ADD96R,.05X.012*%
%ADD95R,.012X.05*%
%ADD86R,.06X.02*%
%ADD68R,.04X.022*%
%ADD101R,.042X.012*%
%ADD99R,.012X.042*%
%ADD74R,.06X.012*%
%ADD19R,.022X.04*%
%ADD118R,.012X.06*%
%ADD94R,.043X.012*%
%ADD93R,.012X.043*%
%ADD138R,.014X.033*%
%ADD137R,.033X.014*%
%ADD72R,.06X.014*%
%ADD71R,.081X.02*%
%ADD61R,.04X.016*%
%ADD49R,.044X.012*%
%ADD39R,.042X.014*%
%ADD33R,.014X.042*%
%ADD139R,.032X.016*%
%ADD131R,.012X.044*%
%ADD117R,.014X.06*%
%ADD100R,.036X.012*%
%ADD98R,.012X.036*%
%ADD126R,.012X.036*%
%ADD124R,.036X.012*%
%ADD112R,.016X.032*%
%ADD105R,.064X.03*%
%ADD104R,.03X.045*%
%ADD132R,.128X.133*%
%ADD127R,.012X.037*%
%ADD125R,.037X.012*%
%ADD60R,.115X.138*%
%ADD41R,.066X.02*%
%ADD114C,.15*%
%ADD70O,.06X.084*%
%ADD67R,.05X.065*%
%ADD134R,.138X.108*%
%ADD92R,.055X.042*%
%ADD78R,.026X.036*%
%ADD20R,.065X.05*%
%ADD141R,.029X.043*%
%ADD42R,.065X.025*%
%ADD110R,.09X.045*%
%ADD106R,.205X.197*%
%ADD88R,.025X.065*%
%ADD73R,.048X.016*%
%ADD44R,.045X.055*%
%ADD135R,.096X.014*%
%ADD64R,.016X.048*%
%ADD43R,.055X.036*%
%ADD32R,.055X.045*%
%ADD142R,.06X.095*%
%ADD129R,.054X.074*%
%ADD54C,.256*%
%ADD128R,.09X.095*%
%ADD89R,.059X.045*%
%ADD58R,.024X.079*%
%AMMACRO113*
4,1,40,.007,.0225,
.008389,.022378,
.009736,.022018,
.011,.021428,
.012142,.020628,
.013128,.019642,
.013928,.0185,
.014518,.017236,
.014878,.015889,
.015,.0145,
.015,-.0145,
.014878,-.015889,
.014518,-.017236,
.013928,-.0185,
.013128,-.019642,
.012142,-.020628,
.011,-.021428,
.009736,-.022018,
.008389,-.022378,
.007,-.0225,
-.007,-.0225,
-.008389,-.022378,
-.009736,-.022018,
-.011,-.021428,
-.012142,-.020628,
-.013128,-.019642,
-.013928,-.0185,
-.014518,-.017236,
-.014878,-.015889,
-.015,-.0145,
-.015,.0145,
-.014878,.015889,
-.014518,.017236,
-.013928,.0185,
-.013128,.019642,
-.012142,.020628,
-.011,.021428,
-.009736,.022018,
-.008389,.022378,
-.007,.0225,
.007,.0225,
0.0*
%
%ADD113MACRO113*%
%ADD109R,.045X.059*%
%ADD97R,.152X.152*%
%AMMACRO76*
4,1,40,.014,.008,
.014,-.008,
.013939,-.008695,
.013759,-.009368,
.013464,-.01,
.013064,-.010571,
.012571,-.011064,
.012,-.011464,
.011368,-.011759,
.010695,-.011939,
.01,-.012,
-.01,-.012,
-.010695,-.011939,
-.011368,-.011759,
-.012,-.011464,
-.012571,-.011064,
-.013064,-.010571,
-.013464,-.01,
-.013759,-.009368,
-.013939,-.008695,
-.014,-.008,
-.014,.008,
-.013939,.008695,
-.013759,.009368,
-.013464,.01,
-.013064,.010571,
-.012571,.011064,
-.012,.011464,
-.011368,.011759,
-.010695,.011939,
-.01,.012,
.01,.012,
.010695,.011939,
.011368,.011759,
.012,.011464,
.012571,.011064,
.013064,.010571,
.013464,.01,
.013759,.009368,
.013939,.008695,
.014,.008,
0.0*
%
%ADD76MACRO76*%
%AMMACRO66*
4,1,40,-.008,.014,
.008,.014,
.008695,.013939,
.009368,.013759,
.01,.013464,
.010571,.013064,
.011064,.012571,
.011464,.012,
.011759,.011368,
.011939,.010695,
.012,.01,
.012,-.01,
.011939,-.010695,
.011759,-.011368,
.011464,-.012,
.011064,-.012571,
.010571,-.013064,
.01,-.013464,
.009368,-.013759,
.008695,-.013939,
.008,-.014,
-.008,-.014,
-.008695,-.013939,
-.009368,-.013759,
-.01,-.013464,
-.010571,-.013064,
-.011064,-.012571,
-.011464,-.012,
-.011759,-.011368,
-.011939,-.010695,
-.012,-.01,
-.012,.01,
-.011939,.010695,
-.011759,.011368,
-.011464,.012,
-.011064,.012571,
-.010571,.013064,
-.01,.013464,
-.009368,.013759,
-.008695,.013939,
-.008,.014,
0.0*
%
%ADD66MACRO66*%
%AMMACRO62*
4,1,40,-.0225,.007,
-.022378,.008389,
-.022018,.009736,
-.021428,.011,
-.020628,.012142,
-.019642,.013128,
-.0185,.013928,
-.017236,.014518,
-.015889,.014878,
-.0145,.015,
.0145,.015,
.015889,.014878,
.017236,.014518,
.0185,.013928,
.019642,.013128,
.020628,.012142,
.021428,.011,
.022018,.009736,
.022378,.008389,
.0225,.007,
.0225,-.007,
.022378,-.008389,
.022018,-.009736,
.021428,-.011,
.020628,-.012142,
.019642,-.013128,
.0185,-.013928,
.017236,-.014518,
.015889,-.014878,
.0145,-.015,
-.0145,-.015,
-.015889,-.014878,
-.017236,-.014518,
-.0185,-.013928,
-.019642,-.013128,
-.020628,-.012142,
-.021428,-.011,
-.022018,-.009736,
-.022378,-.008389,
-.0225,-.007,
-.0225,.007,
0.0*
%
%ADD62MACRO62*%
%ADD59R,.095X.09*%
%ADD23C,.375*%
%ADD102R,.136X.136*%
%ADD38R,.128X.128*%
%ADD22R,.272X.272*%
%ADD120R,.079X.093*%
%AMMACRO53*
4,1,40,-.008,-.012,
.008,-.012,
.008695,-.011939,
.009368,-.011759,
.01,-.011464,
.010571,-.011064,
.011064,-.010571,
.011464,-.01,
.011759,-.009368,
.011939,-.008695,
.012,-.008,
.012,.008,
.011939,.008695,
.011759,.009368,
.011464,.01,
.011064,.010571,
.010571,.011064,
.01,.011464,
.009368,.011759,
.008695,.011939,
.008,.012,
-.008,.012,
-.008695,.011939,
-.009368,.011759,
-.01,.011464,
-.010571,.011064,
-.011064,.010571,
-.011464,.01,
-.011759,.009368,
-.011939,.008695,
-.012,.008,
-.012,-.008,
-.011939,-.008695,
-.011759,-.009368,
-.011464,-.01,
-.011064,-.010571,
-.010571,-.011064,
-.01,-.011464,
-.009368,-.011759,
-.008695,-.011939,
-.008,-.012,
0.0*
%
%ADD53MACRO53*%
%AMMACRO31*
4,1,40,.012,-.008,
.012,.008,
.011939,.008695,
.011759,.009368,
.011464,.01,
.011064,.010571,
.010571,.011064,
.01,.011464,
.009368,.011759,
.008695,.011939,
.008,.012,
-.008,.012,
-.008695,.011939,
-.009368,.011759,
-.01,.011464,
-.010571,.011064,
-.011064,.010571,
-.011464,.01,
-.011759,.009368,
-.011939,.008695,
-.012,.008,
-.012,-.008,
-.011939,-.008695,
-.011759,-.009368,
-.011464,-.01,
-.011064,-.010571,
-.010571,-.011064,
-.01,-.011464,
-.009368,-.011759,
-.008695,-.011939,
-.008,-.012,
.008,-.012,
.008695,-.011939,
.009368,-.011759,
.01,-.011464,
.010571,-.011064,
.011064,-.010571,
.011464,-.01,
.011759,-.009368,
.011939,-.008695,
.012,-.008,
0.0*
%
%ADD31MACRO31*%
%AMMACRO24*
4,1,40,-.007,-.011,
.007,-.011,
.007695,-.010939,
.008368,-.010759,
.009,-.010464,
.009571,-.010064,
.010064,-.009571,
.010464,-.009,
.010759,-.008368,
.010939,-.007695,
.011,-.007,
.011,.007,
.010939,.007695,
.010759,.008368,
.010464,.009,
.010064,.009571,
.009571,.010064,
.009,.010464,
.008368,.010759,
.007695,.010939,
.007,.011,
-.007,.011,
-.007695,.010939,
-.008368,.010759,
-.009,.010464,
-.009571,.010064,
-.010064,.009571,
-.010464,.009,
-.010759,.008368,
-.010939,.007695,
-.011,.007,
-.011,-.007,
-.010939,-.007695,
-.010759,-.008368,
-.010464,-.009,
-.010064,-.009571,
-.009571,-.010064,
-.009,-.010464,
-.008368,-.010759,
-.007695,-.010939,
-.007,-.011,
0.0*
%
%ADD24MACRO24*%
%AMMACRO12*
4,1,40,-.011,.007,
-.011,-.007,
-.010939,-.007695,
-.010759,-.008368,
-.010464,-.009,
-.010064,-.009571,
-.009571,-.010064,
-.009,-.010464,
-.008368,-.010759,
-.007695,-.010939,
-.007,-.011,
.007,-.011,
.007695,-.010939,
.008368,-.010759,
.009,-.010464,
.009571,-.010064,
.010064,-.009571,
.010464,-.009,
.010759,-.008368,
.010939,-.007695,
.011,-.007,
.011,.007,
.010939,.007695,
.010759,.008368,
.010464,.009,
.010064,.009571,
.009571,.010064,
.009,.010464,
.008368,.010759,
.007695,.010939,
.007,.011,
-.007,.011,
-.007695,.010939,
-.008368,.010759,
-.009,.010464,
-.009571,.010064,
-.010064,.009571,
-.010464,.009,
-.010759,.008368,
-.010939,.007695,
-.011,.007,
0.0*
%
%ADD12MACRO12*%
%AMMACRO122*
4,1,6,-.0135,.025,
.0065,.005,
.0135,.005,
.0135,-.005,
.0065,-.005,
-.0135,-.025,
-.0135,.025,
0.0*
%
%ADD122MACRO122*%
%AMMACRO55*
4,1,40,.013,.017,
-.013,.017,
-.013695,.016939,
-.014368,.016759,
-.015,.016464,
-.015571,.016064,
-.016064,.015571,
-.016464,.015,
-.016759,.014368,
-.016939,.013695,
-.017,.013,
-.017,-.013,
-.016939,-.013695,
-.016759,-.014368,
-.016464,-.015,
-.016064,-.015571,
-.015571,-.016064,
-.015,-.016464,
-.014368,-.016759,
-.013695,-.016939,
-.013,-.017,
.013,-.017,
.013695,-.016939,
.014368,-.016759,
.015,-.016464,
.015571,-.016064,
.016064,-.015571,
.016464,-.015,
.016759,-.014368,
.016939,-.013695,
.017,-.013,
.017,.013,
.016939,.013695,
.016759,.014368,
.016464,.015,
.016064,.015571,
.015571,.016064,
.015,.016464,
.014368,.016759,
.013695,.016939,
.013,.017,
0.0*
%
%ADD55MACRO55*%
%AMMACRO47*
4,1,6,.025,.0135,
.005,-.0065,
.005,-.0135,
-.005,-.0135,
-.005,-.0065,
-.025,.0135,
.025,.0135,
0.0*
%
%ADD47MACRO47*%
%AMMACRO16*
4,1,40,.017,-.013,
.017,.013,
.016939,.013695,
.016759,.014368,
.016464,.015,
.016064,.015571,
.015571,.016064,
.015,.016464,
.014368,.016759,
.013695,.016939,
.013,.017,
-.013,.017,
-.013695,.016939,
-.014368,.016759,
-.015,.016464,
-.015571,.016064,
-.016064,.015571,
-.016464,.015,
-.016759,.014368,
-.016939,.013695,
-.017,.013,
-.017,-.013,
-.016939,-.013695,
-.016759,-.014368,
-.016464,-.015,
-.016064,-.015571,
-.015571,-.016064,
-.015,-.016464,
-.014368,-.016759,
-.013695,-.016939,
-.013,-.017,
.013,-.017,
.013695,-.016939,
.014368,-.016759,
.015,-.016464,
.015571,-.016064,
.016064,-.015571,
.016464,-.015,
.016759,-.014368,
.016939,-.013695,
.017,-.013,
0.0*
%
%ADD16MACRO16*%
%AMMACRO83*
4,1,40,-.008,-.009,
-.008695,-.008939,
-.009368,-.008759,
-.01,-.008464,
-.010571,-.008064,
-.011064,-.007571,
-.011464,-.007,
-.011759,-.006368,
-.011939,-.005695,
-.012,-.005,
-.012,.005,
-.011939,.005695,
-.011759,.006368,
-.011464,.007,
-.011064,.007571,
-.010571,.008064,
-.01,.008464,
-.009368,.008759,
-.008695,.008939,
-.008,.009,
.008,.009,
.008695,.008939,
.009368,.008759,
.01,.008464,
.010571,.008064,
.011064,.007571,
.011464,.007,
.011759,.006368,
.011939,.005695,
.012,.005,
.012,-.005,
.011939,-.005695,
.011759,-.006368,
.011464,-.007,
.011064,-.007571,
.010571,-.008064,
.01,-.008464,
.009368,-.008759,
.008695,-.008939,
.008,-.009,
-.008,-.009,
0.0*
%
%ADD83MACRO83*%
%AMMACRO107*
4,1,40,-.023,.013,
-.023,-.013,
-.022939,-.013695,
-.022759,-.014368,
-.022464,-.015,
-.022064,-.015571,
-.021571,-.016064,
-.021,-.016464,
-.020368,-.016759,
-.019695,-.016939,
-.019,-.017,
.019,-.017,
.019695,-.016939,
.020368,-.016759,
.021,-.016464,
.021571,-.016064,
.022064,-.015571,
.022464,-.015,
.022759,-.014368,
.022939,-.013695,
.023,-.013,
.023,.013,
.022939,.013695,
.022759,.014368,
.022464,.015,
.022064,.015571,
.021571,.016064,
.021,.016464,
.020368,.016759,
.019695,.016939,
.019,.017,
-.019,.017,
-.019695,.016939,
-.020368,.016759,
-.021,.016464,
-.021571,.016064,
-.022064,.015571,
-.022464,.015,
-.022759,.014368,
-.022939,.013695,
-.023,.013,
0.0*
%
%ADD107MACRO107*%
%AMMACRO48*
4,1,20,-.0655,.1095,
-.051,.1095,
-.051,.12,
-.0375,.12,
-.0375,.1095,
.0375,.1095,
.0375,.12,
.051,.12,
.051,.1095,
.0655,.1095,
.0655,-.1095,
.051,-.1095,
.051,-.12,
.0375,-.12,
.0375,-.1095,
-.0375,-.1095,
-.0375,-.12,
-.051,-.12,
-.051,-.1095,
-.0655,-.1095,
-.0655,.1095,
0.0*
%
%ADD48MACRO48*%
%AMMACRO57*
4,1,15,-.0275,-.115,
-.0275,.115,
.0275,.115,
.0275,.06339,
.02431,.059697,
.021809,.055506,
.020074,.050945,
.019157,.046151,
.019087,.041272,
.019865,.036454,
.021468,.031844,
.023847,.027583,
.02693,.0238,
.0275,.02323,
.0275,-.115,
-.0275,-.115,
0.0*
%
%ADD57MACRO57*%
%AMMACRO52*
4,1,40,-.008,-.012,
.008,-.012,
.008695,-.011939,
.009368,-.011759,
.01,-.011464,
.010571,-.011064,
.011064,-.010571,
.011464,-.01,
.011759,-.009368,
.011939,-.008695,
.012,-.008,
.012,.008,
.011939,.008695,
.011759,.009368,
.011464,.01,
.011064,.010571,
.010571,.011064,
.01,.011464,
.009368,.011759,
.008695,.011939,
.008,.012,
-.008,.012,
-.008695,.011939,
-.009368,.011759,
-.01,.011464,
-.010571,.011064,
-.011064,.010571,
-.011464,.01,
-.011759,.009368,
-.011939,.008695,
-.012,.008,
-.012,-.008,
-.011939,-.008695,
-.011759,-.009368,
-.011464,-.01,
-.011064,-.010571,
-.010571,-.011064,
-.01,-.011464,
-.009368,-.011759,
-.008695,-.011939,
-.008,-.012,
0.0*
%
%ADD52MACRO52*%
%AMMACRO30*
4,1,40,.012,-.008,
.012,.008,
.011939,.008695,
.011759,.009368,
.011464,.01,
.011064,.010571,
.010571,.011064,
.01,.011464,
.009368,.011759,
.008695,.011939,
.008,.012,
-.008,.012,
-.008695,.011939,
-.009368,.011759,
-.01,.011464,
-.010571,.011064,
-.011064,.010571,
-.011464,.01,
-.011759,.009368,
-.011939,.008695,
-.012,.008,
-.012,-.008,
-.011939,-.008695,
-.011759,-.009368,
-.011464,-.01,
-.011064,-.010571,
-.010571,-.011064,
-.01,-.011464,
-.009368,-.011759,
-.008695,-.011939,
-.008,-.012,
.008,-.012,
.008695,-.011939,
.009368,-.011759,
.01,-.011464,
.010571,-.011064,
.011064,-.010571,
.011464,-.01,
.011759,-.009368,
.011939,-.008695,
.012,-.008,
0.0*
%
%ADD30MACRO30*%
%AMMACRO25*
4,1,40,-.007,-.011,
.007,-.011,
.007695,-.010939,
.008368,-.010759,
.009,-.010464,
.009571,-.010064,
.010064,-.009571,
.010464,-.009,
.010759,-.008368,
.010939,-.007695,
.011,-.007,
.011,.007,
.010939,.007695,
.010759,.008368,
.010464,.009,
.010064,.009571,
.009571,.010064,
.009,.010464,
.008368,.010759,
.007695,.010939,
.007,.011,
-.007,.011,
-.007695,.010939,
-.008368,.010759,
-.009,.010464,
-.009571,.010064,
-.010064,.009571,
-.010464,.009,
-.010759,.008368,
-.010939,.007695,
-.011,.007,
-.011,-.007,
-.010939,-.007695,
-.010759,-.008368,
-.010464,-.009,
-.010064,-.009571,
-.009571,-.010064,
-.009,-.010464,
-.008368,-.010759,
-.007695,-.010939,
-.007,-.011,
0.0*
%
%ADD25MACRO25*%
%AMMACRO13*
4,1,40,-.011,.007,
-.011,-.007,
-.010939,-.007695,
-.010759,-.008368,
-.010464,-.009,
-.010064,-.009571,
-.009571,-.010064,
-.009,-.010464,
-.008368,-.010759,
-.007695,-.010939,
-.007,-.011,
.007,-.011,
.007695,-.010939,
.008368,-.010759,
.009,-.010464,
.009571,-.010064,
.010064,-.009571,
.010464,-.009,
.010759,-.008368,
.010939,-.007695,
.011,-.007,
.011,.007,
.010939,.007695,
.010759,.008368,
.010464,.009,
.010064,.009571,
.009571,.010064,
.009,.010464,
.008368,.010759,
.007695,.010939,
.007,.011,
-.007,.011,
-.007695,.010939,
-.008368,.010759,
-.009,.010464,
-.009571,.010064,
-.010064,.009571,
-.010464,.009,
-.010759,.008368,
-.010939,.007695,
-.011,.007,
0.0*
%
%ADD13MACRO13*%
%ADD143C,.012*%
%ADD144C,.013*%
%ADD145C,.015*%
%ADD146C,.017*%
%ADD147C,.004*%
%ADD148C,.005*%
%ADD149C,.006*%
%ADD150C,.007*%
%ADD151C,.008*%
%ADD152C,.0035*%
%ADD153C,.0049*%
%ADD154C,.00375*%
%ADD155C,.00538*%
%ADD156C,.00575*%
%ADD159O,.08402X.10802*%
%ADD161C,.04404*%
%ADD160C,.06604*%
%ADD158R,.07304X.03004*%
%ADD157R,.008X.008*%
G75*
%LPD*%
G75*
G36*
G01X26483Y752780D02*
X11125Y722062D01*
X10896D01*
X10750Y721916D01*
Y721708D01*
X10896Y721562D01*
X11000D01*
Y11000D01*
X25492D01*
Y3004D01*
X3937D01*
G02X3004Y3937I0J933D01*
G01Y723480D01*
G02X3103Y723897I933J-1D01*
G01X21284Y760260D01*
G02X22118Y760776I835J-417D01*
G01X386150D01*
G02X386984Y760260I-1J-933D01*
G01X405165Y723897D01*
G02X405264Y723480I-834J-418D01*
G01Y722062D01*
X397143D01*
X381785Y752780D01*
X379625D01*
X379565Y752853D01*
G03X348722Y752780I-15392J-12696D01*
G01X64664D01*
G03X33762I-15451J-12623D01*
G01X26483D01*
G37*
G36*
G01X74430Y57500D02*
X71560Y60370D01*
X67720D01*
X67430Y60660D01*
Y67730D01*
X68520Y68820D01*
X79240D01*
X80900Y67160D01*
Y57500D01*
X74430D01*
G37*
G36*
G01X56370Y51240D02*
X52050Y55560D01*
X47280D01*
X46430Y56410D01*
Y63400D01*
X47020Y63990D01*
X47330D01*
X48240Y64900D01*
X58280D01*
X59930Y63250D01*
Y51320D01*
X59850Y51240D01*
X59432D01*
X59392Y51259D01*
G03X58710Y51412I-683J-1449D01*
G01X57310D01*
G03X56628Y51259I1J-1602D01*
G01X56588Y51240D01*
X56370D01*
G37*
G36*
G01X106950Y39910D02*
X106498Y40362D01*
X106731Y40595D01*
X106852Y40549D01*
G03X105370Y47052I1416J3743D01*
G02X104680Y47327I-290J275D01*
G01Y49610D01*
X106630Y51560D01*
X113400D01*
X114080Y50880D01*
Y12700D01*
X113040Y11660D01*
X68750D01*
X67250Y13160D01*
Y33582D01*
X67265Y33618D01*
G03Y35280I-2039J831D01*
G01X67250Y35316D01*
Y54880D01*
X67650Y55280D01*
X75420D01*
X76438Y56298D01*
X78214D01*
X78251Y56283D01*
G03X78870Y56158I620J1477D01*
G01X80272D01*
X81714Y54716D01*
Y53575D01*
G03X83316Y51974I1601J0D01*
G01X83660D01*
Y47879D01*
G02X83028Y47553I-400J0D01*
G03Y41031I-2320J-3261D01*
G02X83660Y40705I232J-326D01*
G01Y39590D01*
X81960Y37890D01*
Y36045D01*
X81944Y36008D01*
G03X81960Y32853I3686J-1559D01*
G01Y28190D01*
X106790D01*
X106950Y28350D01*
Y32709D01*
G03Y36189I-3604J1740D01*
G01Y39910D01*
G37*
G36*
G01X34795Y38223D02*
Y40808D01*
X32192D01*
Y38244D01*
G03Y30654I1272J-3795D01*
G01Y13904D01*
X34796D01*
Y21519D01*
G02X35478Y21802I400J0D01*
G01X35960Y21320D01*
X36101D01*
X36151Y21286D01*
G03X40670Y21320I2235J3320D01*
G01X49950D01*
X50030Y21400D01*
Y32640D01*
X47360Y35310D01*
Y50020D01*
X47770Y50430D01*
X55481D01*
X55872Y50038D01*
X60348D01*
X60739Y50430D01*
X61820D01*
X65870Y46380D01*
Y12500D01*
X64585Y11215D01*
X29285D01*
X28000Y12500D01*
Y22900D01*
X26700Y24200D01*
Y41500D01*
X27900Y42700D01*
X34800D01*
X38460Y39040D01*
Y32070D01*
X35478Y29088D01*
G02X34796Y29371I-282J283D01*
G01Y30675D01*
G03X34795Y38223I-1332J3774D01*
G37*
G36*
G01X88400Y501300D02*
X88204Y501104D01*
X88157Y501089D01*
G03X87397Y500700I743J-2389D01*
G01X46711D01*
X24966Y522445D01*
Y571359D01*
X27920Y574313D01*
X43006D01*
X44600Y572719D01*
Y562123D01*
X41936Y559459D01*
X35929D01*
X34368Y557898D01*
Y550918D01*
X34349Y550878D01*
G03X34198Y550200I1451J-679D01*
G01Y548800D01*
G03X34349Y548122I1602J1D01*
G01X34368Y548082D01*
Y539146D01*
X34367Y539135D01*
G03X34356Y538954I1591J-188D01*
G01Y537554D01*
G03X34367Y537373I1602J7D01*
G01X34368Y537362D01*
Y535716D01*
X34382Y535702D01*
Y533581D01*
X34380Y533567D01*
G03X34364Y533338I1585J-226D01*
G01Y531938D01*
G03X34380Y531709I1601J-3D01*
G01X34382Y531695D01*
Y530297D01*
X56879Y507800D01*
X67500D01*
X67700Y507600D01*
X74405D01*
X74421Y507598D01*
G03X74673Y507578I252J1581D01*
G01X76073D01*
G03X76325Y507598I0J1601D01*
G01X76341Y507600D01*
X80032D01*
X80052Y507596D01*
G03X80368Y507564I319J1570D01*
G01X81768D01*
G03X82084Y507596I-3J1602D01*
G01X82104Y507600D01*
X85600D01*
X85650Y507650D01*
X88250D01*
X88400Y507500D01*
Y501300D01*
G37*
G36*
G01X115884Y629011D02*
X115124Y628252D01*
X115040Y628253D01*
G03X112527Y626088I-34J-2502D01*
G01X112518Y626021D01*
X111798Y625302D01*
Y624926D01*
X110436Y623564D01*
X100200D01*
X83936Y607300D01*
X76278D01*
X60928Y591950D01*
Y583372D01*
X61800Y582500D01*
X66589D01*
G03X67000Y582076I1263J813D01*
G01Y581400D01*
X66600Y581000D01*
X61900D01*
X60200Y579300D01*
X57250D01*
X54975Y581575D01*
Y602400D01*
X74322Y621747D01*
X82289D01*
X87050Y626508D01*
X90508D01*
X95268Y631268D01*
X104232D01*
X107964Y635001D01*
Y667364D01*
X110300Y669700D01*
X122900D01*
X124807Y667793D01*
Y660700D01*
X124700D01*
Y659400D01*
X123698Y658398D01*
G03X123408Y658109I1403J-1697D01*
G01X123402Y658102D01*
X115884Y650584D01*
Y629011D01*
G37*
G36*
G01X81300Y623827D02*
X74379D01*
X74371Y623835D01*
X74195D01*
X73753Y624277D01*
Y631778D01*
X74218Y632243D01*
X80459D01*
X80471Y632231D01*
X81617D01*
X81971Y631877D01*
Y624498D01*
X81300Y623827D01*
G37*
G36*
G01X61454Y652008D02*
X62450Y651012D01*
Y648683D01*
X62449Y648675D01*
G03X62444Y648550I1597J-126D01*
G01Y647150D01*
G03X62449Y647025I1602J1D01*
G01X62450Y647017D01*
Y637250D01*
X62200Y637000D01*
X55714D01*
X54426Y638288D01*
Y657166D01*
X55460Y658200D01*
X61000D01*
X61200Y658000D01*
Y652400D01*
X61454Y652146D01*
Y652008D01*
G37*
G36*
G01X65614Y634986D02*
X63800Y636800D01*
Y644100D01*
X63830Y644130D01*
Y645030D01*
X64280Y645480D01*
X66600D01*
X67300Y646180D01*
Y652000D01*
X65056Y654244D01*
Y658200D01*
X73100D01*
X73148Y658248D01*
X73316D01*
Y661390D01*
X78011D01*
X78400Y661000D01*
Y659800D01*
X79400Y658800D01*
X87598D01*
Y658702D01*
X93098D01*
X94400Y657400D01*
Y637300D01*
X92086Y634986D01*
X86898D01*
X86864Y634999D01*
G03X86300Y635102I-565J-1499D01*
G01X84700D01*
G03X84136Y634999I1J-1602D01*
G01X84102Y634986D01*
X65614D01*
G37*
G36*
G01X98000Y634000D02*
X96000Y636000D01*
Y658450D01*
X94400Y660050D01*
X81550D01*
X79000Y662600D01*
X78758D01*
Y662634D01*
X72156D01*
Y662602D01*
X72098D01*
Y659498D01*
X72052Y659452D01*
X59272D01*
Y662634D01*
X58566D01*
X58550Y662650D01*
X50100D01*
X49400Y663350D01*
Y667100D01*
X48500Y668000D01*
Y672400D01*
X48700Y672600D01*
X48863D01*
X48877Y672598D01*
G03X49100Y672582I226J1586D01*
G01X50700D01*
G03X50923Y672598I-3J1602D01*
G01X50937Y672600D01*
X51500D01*
X52670Y671430D01*
Y669066D01*
X53234D01*
X53300Y669000D01*
X59300D01*
X59400Y669100D01*
Y672291D01*
X71360D01*
X71698Y671952D01*
Y670302D01*
X72100Y669901D01*
Y669300D01*
X72156Y669245D01*
Y669066D01*
X78758D01*
Y669098D01*
X88798D01*
X88799Y669100D01*
X102600D01*
X106715Y664985D01*
Y635615D01*
X105100Y634000D01*
X98000D01*
G37*
G36*
G01X81768Y683268D02*
X81812Y683283D01*
G03X82817Y684288I-512J1517D01*
G01X82832Y684332D01*
X84200Y685700D01*
X90400D01*
X90900Y685200D01*
Y672900D01*
X88300Y670300D01*
X82649D01*
G03X82584Y670302I-82J-1599D01*
G01X80984D01*
G03X80919Y670300I17J-1601D01*
G01X78758D01*
Y670310D01*
X73390D01*
X73316Y670384D01*
Y673452D01*
X71898D01*
X71800Y673550D01*
X65056D01*
Y678950D01*
X67406Y681300D01*
X70258D01*
X70309Y681248D01*
X77834D01*
X77884Y681298D01*
X78855D01*
X78856Y681300D01*
X79800D01*
X81768Y683268D01*
G37*
G36*
G01X89939Y717877D02*
X77876D01*
X76638Y719115D01*
Y725657D01*
X77600Y726619D01*
X90503D01*
X90637Y726485D01*
Y718575D01*
X89939Y717877D01*
G37*
G36*
G01X109197Y53525D02*
Y429331D01*
G02X124134Y444268I14937J0D01*
G01X125760D01*
G03X129864I2052J798D01*
G01X208348D01*
Y436272D01*
X124134D01*
G03X117193Y429331I0J-6941D01*
G01Y53525D01*
X109197D01*
G37*
G36*
G01X100187Y671541D02*
X92575D01*
X92425Y671691D01*
Y685192D01*
X92825Y685592D01*
X100100D01*
X101646Y684046D01*
Y673000D01*
X100187Y671541D01*
G37*
G36*
G01X130349Y697215D02*
X128349Y699215D01*
Y703200D01*
X128778D01*
Y704478D01*
X128900Y704600D01*
Y734300D01*
X129800Y735200D01*
X135400D01*
X136000Y734600D01*
Y726200D01*
X136410Y725790D01*
X138750D01*
Y726850D01*
X140100D01*
X140120Y726830D01*
Y725890D01*
X140180Y725830D01*
X140190Y725840D01*
X141260D01*
Y713043D01*
X141349D01*
Y699215D01*
X139349Y697215D01*
X136402D01*
Y697402D01*
X132998D01*
Y697215D01*
X130349D01*
G37*
G36*
G01X116900Y684215D02*
X111349Y689766D01*
Y693715D01*
X112317Y694683D01*
X119248D01*
Y694047D01*
G03X120849Y692446I1601J0D01*
G01X122249D01*
G03X123850Y694047I0J1601D01*
G01Y694683D01*
X137881D01*
X138849Y693715D01*
Y684715D01*
X138349Y684215D01*
X116900D01*
G37*
G36*
G01X161420Y714715D02*
X143349D01*
X142849Y715215D01*
Y734900D01*
X145500Y737551D01*
Y741838D01*
X145850Y742188D01*
X160542D01*
X162430Y740300D01*
Y715725D01*
X161420Y714715D01*
G37*
G36*
G01X122211D02*
X121046Y715880D01*
X108293D01*
X107581Y715168D01*
X95092D01*
X93258Y717001D01*
Y726597D01*
X91236Y728619D01*
Y733183D01*
X98817D01*
X98849Y733215D01*
X120520D01*
X122095Y734790D01*
X127510D01*
X127625Y734675D01*
Y727210D01*
X127412Y726996D01*
X127268D01*
Y715634D01*
X126349Y714715D01*
X122211D01*
G37*
G36*
G01X119980Y735950D02*
X90632D01*
X89700Y736882D01*
Y746500D01*
X89915Y746715D01*
X127281D01*
X128003Y745993D01*
Y737640D01*
X127834Y737471D01*
X121501D01*
X119980Y735950D01*
G37*
G36*
G01X154900Y512300D02*
X154396Y512804D01*
Y514796D01*
X154900Y515300D01*
Y515732D01*
X155714Y516546D01*
Y517694D01*
G02X155925Y517893I200J0D01*
G03X156021Y517890I98J1599D01*
G01X157421D01*
G03X157971Y517988I-2J1602D01*
G01X158004Y518000D01*
X159528D01*
X159556Y517991D01*
G03X160027Y517920I472J1531D01*
G01X161280D01*
X161300Y517900D01*
Y512300D01*
X154900D01*
G37*
G36*
G01X145100Y636400D02*
X144800Y636700D01*
Y642500D01*
X148200Y645900D01*
X150900D01*
X151100Y645700D01*
Y643900D01*
X150100Y642900D01*
Y638927D01*
X150578Y638449D01*
X152863D01*
X153046Y638266D01*
Y636699D01*
X152747Y636400D01*
X145100D01*
G37*
G36*
G01X182731Y635643D02*
X182389Y635985D01*
X178098D01*
X178013Y635900D01*
X177865D01*
G03X177800Y635902I-82J-1599D01*
G01X176400D01*
G03X176335Y635900I17J-1601D01*
G01X173765D01*
G03X173700Y635902I-82J-1599D01*
G01X172298D01*
X171400Y636800D01*
Y641400D01*
X171900Y641900D01*
X173750D01*
X174127Y641523D01*
Y639786D01*
X175211Y638702D01*
X177077D01*
X177383Y639008D01*
X179045D01*
G03X179662Y638518I1656J1451D01*
G01X179874Y638306D01*
X180242D01*
X180262Y638302D01*
G03X181138I438J2158D01*
G01X181158Y638306D01*
X182173D01*
X184587Y640720D01*
X192633D01*
X193067Y641154D01*
X193971D01*
X194622Y640503D01*
Y635615D01*
X194176Y635170D01*
X192776D01*
G03X192422Y635130I2J-1602D01*
G01X192400Y635125D01*
X190452D01*
X190430Y635130D01*
G03X190076Y635170I-356J-1562D01*
G01X188676D01*
G03X188322Y635130I2J-1602D01*
G01X188300Y635125D01*
X186352D01*
X186330Y635130D01*
G03X185976Y635170I-356J-1562D01*
G01X184576D01*
G03X184222Y635130I2J-1602D01*
G01X184200Y635125D01*
X183249D01*
X183180Y635194D01*
G03X182747Y635632I-1334J-886D01*
G01X182731Y635643D01*
G37*
G36*
G01X189330Y703670D02*
X188500Y704500D01*
Y715400D01*
X190500Y717400D01*
X203500D01*
X206800Y714100D01*
X228000D01*
X228900Y713200D01*
Y704900D01*
X227670Y703670D01*
X189330D01*
G37*
G36*
G01X230600Y711400D02*
X230102Y711898D01*
Y713698D01*
X229800Y713999D01*
Y714600D01*
X229100Y715300D01*
X228499D01*
X228498Y715302D01*
X226758D01*
X226726Y715313D01*
G03X226200Y715402I-527J-1513D01*
G01X224600D01*
G03X224074Y715313I1J-1602D01*
G01X224042Y715302D01*
X207422D01*
X203924Y718800D01*
X173400D01*
X172812Y719388D01*
Y742000D01*
X174512Y743700D01*
X234200D01*
X235400Y742500D01*
Y712500D01*
X234300Y711400D01*
X230600D01*
G37*
G36*
G01X249568Y715268D02*
X240332D01*
X239050Y716550D01*
Y742500D01*
X240025Y743475D01*
X250525D01*
X251900Y742100D01*
Y717600D01*
X249568Y715268D01*
G37*
G36*
G01X332700Y79700D02*
X330800Y81600D01*
Y105183D01*
X333576Y107959D01*
X347110D01*
X348149Y108998D01*
X354565D01*
X355509Y108054D01*
Y94990D01*
X350900Y90381D01*
Y88514D01*
G03Y84556I2643J-1979D01*
G01Y81700D01*
X348900Y79700D01*
X332700D01*
G37*
G36*
G01X304745Y194830D02*
X304032Y195543D01*
Y197124D01*
X304054Y197146D01*
Y198454D01*
X305450Y199850D01*
X308426D01*
X311600Y203024D01*
X319832D01*
X320729Y203921D01*
X322339D01*
X323031Y203229D01*
Y195615D01*
X322287Y194871D01*
X319918D01*
Y194918D01*
X309414D01*
Y194871D01*
X306592D01*
X306552Y194830D01*
X304745D01*
G37*
G36*
G01X302620Y184348D02*
X299742Y181470D01*
X294307D01*
X292851Y182926D01*
Y191343D01*
X292882Y191374D01*
Y199915D01*
X301714D01*
Y196162D01*
X304247Y193629D01*
X307227D01*
X307662Y193194D01*
Y189324D01*
X304738Y186400D01*
X304672D01*
X304432Y186160D01*
X304400Y186145D01*
G03X302620Y184348I1506J-3271D01*
G37*
G36*
G01X335882Y187374D02*
X331382Y191874D01*
Y206374D01*
X332482Y207474D01*
X349282D01*
X353382Y203374D01*
Y196692D01*
X354160Y195914D01*
Y195912D01*
X354161D01*
X355752Y194322D01*
Y191226D01*
X355350Y190824D01*
X352532D01*
X352100Y191256D01*
Y194574D01*
X350055Y196619D01*
X344807D01*
X344233Y196046D01*
X344164D01*
X343298Y195180D01*
Y195110D01*
X343282Y195094D01*
Y187656D01*
X343000Y187374D01*
X335882D01*
G37*
G36*
G01X324207Y208799D02*
X322494Y210512D01*
X310486D01*
Y212562D01*
X319918D01*
Y212727D01*
X323356D01*
X325219Y214590D01*
Y219597D01*
X328771Y223148D01*
X347101D01*
X348327Y224374D01*
X356282D01*
X357396Y223260D01*
Y213588D01*
X352607Y208799D01*
X324207D01*
G37*
G36*
G01X304059Y216403D02*
X303997Y216466D01*
X303441D01*
X302932Y216974D01*
X292982D01*
X292682Y217274D01*
Y227974D01*
X293019Y228310D01*
X301232D01*
X304270Y225272D01*
X304733D01*
X304882Y225124D01*
X307382D01*
X309282Y227024D01*
Y230287D01*
X310455Y231460D01*
X319196D01*
X319582Y231074D01*
Y220374D01*
X319382Y220174D01*
X308382D01*
X307987Y219779D01*
Y217929D01*
X307982Y217924D01*
Y217300D01*
X307085Y216403D01*
X304059D01*
G37*
G36*
G01X335800Y607700D02*
X327600D01*
X327100Y608200D01*
Y622700D01*
X327900Y623500D01*
X336300D01*
X337100Y622700D01*
Y609000D01*
X335800Y607700D01*
G37*
G36*
G01X336600Y641250D02*
Y637412D01*
G03X336542Y634244I1500J-1612D01*
G01X336600Y634186D01*
Y634000D01*
X335400Y632800D01*
X322136D01*
X319586Y635350D01*
X319344D01*
Y635384D01*
X312742D01*
Y632306D01*
X312636Y632200D01*
X299858D01*
Y635384D01*
X299152D01*
X299136Y635400D01*
X290443D01*
X288886Y636957D01*
Y640950D01*
X289686Y641750D01*
X299886D01*
X299986Y641850D01*
Y645041D01*
X312686D01*
Y642050D01*
X312742Y641994D01*
Y641816D01*
X319344D01*
Y641850D01*
X319600D01*
X320650Y642900D01*
X321235D01*
G03X321300Y642898I82J1599D01*
G01X322900D01*
G03X322965Y642900I-17J1601D01*
G01X328700D01*
G03X332100I1700J1400D01*
G01X333187D01*
G03X335317Y642386I1513J1600D01*
G01X335431Y642419D01*
X336600Y641250D01*
G37*
G36*
G01X313902Y643060D02*
Y646202D01*
X313888D01*
Y646252D01*
X313648D01*
X313600Y646300D01*
X305642D01*
Y651644D01*
X305586D01*
Y653586D01*
X307900Y655900D01*
Y660500D01*
X308600Y661200D01*
X323100D01*
X324000Y660300D01*
Y650979D01*
X323050Y650029D01*
Y647632D01*
X323986Y646696D01*
Y644686D01*
X323402Y644102D01*
X320152D01*
X320151Y644100D01*
X320000D01*
X318960Y643060D01*
X313902D01*
G37*
G36*
G01X314500Y598200D02*
X302252D01*
X301160Y599292D01*
Y603594D01*
X301866Y604300D01*
X314480D01*
X314490Y604310D01*
X314892Y603908D01*
Y598592D01*
X314500Y598200D01*
G37*
G36*
G01X301200Y606200D02*
X298968Y608432D01*
Y610200D01*
X299000Y610232D01*
Y625314D01*
X300400Y626714D01*
Y630850D01*
X300500Y630950D01*
X301586D01*
X301786Y630750D01*
Y625150D01*
X302040Y624896D01*
Y624758D01*
X303036Y623762D01*
Y609564D01*
X303200Y609400D01*
Y606900D01*
X302500Y606200D01*
X301200D01*
G37*
G36*
G01X309400Y606700D02*
X309100Y607000D01*
Y610700D01*
X308700Y611100D01*
X304800D01*
X304469Y611431D01*
X304471Y611516D01*
G03X304472Y611550I-1600J64D01*
G01Y613150D01*
G03X304395Y613638I-1602J-3D01*
G01X304386Y613667D01*
Y616850D01*
X304416Y616880D01*
Y617780D01*
X304812Y618176D01*
X306148D01*
G03X306539Y618224I2J1601D01*
G01X306563Y618230D01*
X307186D01*
X307886Y618930D01*
Y624750D01*
X305642Y626994D01*
Y630950D01*
X313686D01*
X313734Y630998D01*
X313902D01*
Y631766D01*
X313988Y631852D01*
Y634140D01*
X318596D01*
X318986Y633750D01*
Y632550D01*
X319986Y631550D01*
X334850D01*
X335400Y631000D01*
Y625400D01*
X335200Y625200D01*
X326000D01*
X325100Y624300D01*
Y608600D01*
X319850D01*
X319400Y609050D01*
X319081D01*
X319043Y609067D01*
G03X318400Y609202I-644J-1467D01*
G01X316800D01*
G03X316157Y609067I1J-1602D01*
G01X316119Y609050D01*
X315200D01*
X314900Y608750D01*
Y607000D01*
X314600Y606700D01*
X309400D01*
G37*
G36*
G01X334298Y705251D02*
X336998Y702549D01*
Y701732D01*
X337068Y701662D01*
Y693092D01*
G03Y690068I1601J-1512D01*
G01Y682232D01*
X332136Y677300D01*
X325763D01*
X324600Y678463D01*
Y679700D01*
X326000Y681100D01*
Y681979D01*
X326121Y682100D01*
Y694121D01*
X326400Y694400D01*
X327850D01*
X328416Y694966D01*
G03X328972Y695522I-1254J1810D01*
G01X329400Y695950D01*
Y701024D01*
X329404Y701044D01*
G03Y701956I-2154J456D01*
G01X329400Y701976D01*
Y703100D01*
X328537Y703963D01*
X311096D01*
X310369Y704690D01*
Y705371D01*
X308920Y706820D01*
X308678D01*
Y706854D01*
X302076D01*
Y706822D01*
X302018D01*
Y703718D01*
X302000Y703700D01*
X289192D01*
Y706854D01*
X288486D01*
X288470Y706870D01*
X278770D01*
X278440Y707200D01*
X278428Y707218D01*
G03X278220Y707497I-2105J-1352D01*
G01Y712420D01*
X279020Y713220D01*
X289220D01*
X289320Y713320D01*
Y716511D01*
X302020D01*
Y713520D01*
X302076Y713464D01*
Y713286D01*
X308678D01*
Y713320D01*
X310839D01*
G03X310904Y713318I82J1599D01*
G01X312504D01*
G03X312569Y713320I-17J1601D01*
G01X331384D01*
X334298Y710407D01*
Y705251D01*
G37*
G36*
G01X308678Y714522D02*
Y714530D01*
X303310D01*
X303236Y714604D01*
Y717672D01*
X303222D01*
Y717722D01*
X301768D01*
X301720Y717770D01*
X294976D01*
Y723114D01*
X294920D01*
Y732855D01*
X295709Y733644D01*
X311439D01*
X313320Y731763D01*
Y714920D01*
X312922Y714522D01*
X308678D01*
G37*
G36*
G01X312233Y672987D02*
X311795Y672549D01*
X311706Y672553D01*
G03X311155Y672510I-106J-2199D01*
G01X311135Y672506D01*
X297594D01*
X297500Y672600D01*
Y677200D01*
X298070Y677770D01*
X311816D01*
X312233Y677353D01*
Y672987D01*
G37*
G36*
G01X286018Y681220D02*
X285002Y682236D01*
Y682900D01*
G03X285000Y682965I-1601J-17D01*
G01Y684835D01*
G03X285002Y684900I-1599J82D01*
G01Y686500D01*
G03X285000Y686565I-1601J-17D01*
G01Y701552D01*
X285868Y702420D01*
X290920D01*
X291174Y702166D01*
Y697026D01*
X291200D01*
Y696300D01*
X292370Y695130D01*
Y681870D01*
X291898Y681398D01*
X291891Y681392D01*
G03X291707Y681220I1409J-1692D01*
G01X286018D01*
G37*
G36*
G01X295580Y680520D02*
X294998Y681102D01*
X294992Y681109D01*
G03X294709Y681392I-1692J-1409D01*
G01X294702Y681398D01*
X293600Y682500D01*
Y683203D01*
X293602Y683218D01*
G03X293620Y683453I-1584J239D01*
G01Y684853D01*
G03X293602Y685088I-1602J-4D01*
G01X293600Y685103D01*
Y687187D01*
X293601Y687195D01*
G03X293606Y687320I-1597J126D01*
G01Y688920D01*
G03X293601Y689045I-1602J-1D01*
G01X293600Y689053D01*
Y689300D01*
X293900Y689600D01*
X296420D01*
X297220Y690400D01*
Y695880D01*
X296532Y696568D01*
G03X296168Y696932I-1728J-1364D01*
G01X294976Y698124D01*
Y702420D01*
X303020D01*
X303068Y702468D01*
X303236D01*
Y705610D01*
X307930D01*
X308320Y705220D01*
Y704020D01*
X309672Y702668D01*
X323272D01*
X324320Y701620D01*
Y681520D01*
X323320Y680520D01*
X322676D01*
X322640Y680535D01*
G03X320960I-840J-2035D01*
G01X320924Y680520D01*
X318996D01*
X318970Y680527D01*
G03X317830I-570J-2127D01*
G01X317804Y680520D01*
X317107D01*
G03X315720Y681322I-1388J-800D01*
G01X314120D01*
G03X312733Y680520I1J-1602D01*
G01X295580D01*
G37*
G36*
G01X378361Y125309D02*
X377529Y124477D01*
X373351D01*
X371655Y122781D01*
Y107195D01*
X366647Y102187D01*
X357452D01*
X356710Y102928D01*
Y108552D01*
X356461Y108801D01*
Y113774D01*
X357186Y114498D01*
X364702D01*
Y114948D01*
X365040Y115287D01*
Y123778D01*
X364072Y124746D01*
X364056Y124786D01*
G03X363557Y125557I-2057J-784D01*
G01X360682Y128432D01*
Y140290D01*
X361317Y140926D01*
X377574D01*
X378361Y140139D01*
Y125309D01*
G37*
G36*
G01X350852Y189064D02*
X350212Y188424D01*
X344972D01*
X344500Y188896D01*
Y189009D01*
G03X344502Y189074I-1599J82D01*
G01Y190674D01*
G03X344500Y190739I-1601J-17D01*
G01Y192666D01*
X344503Y192685D01*
G03X344530Y192978I-1574J293D01*
G01Y194378D01*
G03X344517Y194588I-1601J6D01*
G01X344504Y194686D01*
X344662Y194844D01*
X350002D01*
X350852Y193994D01*
Y189064D01*
G37*
G36*
G01X368408Y203900D02*
X368041Y203533D01*
X367928Y203564D01*
G03X367499Y203622I-427J-1543D01*
G01X365899D01*
G03X365744Y203615I-5J-1601D01*
G01X365650Y203606D01*
X365382Y203874D01*
Y206274D01*
X365982Y206874D01*
Y212874D01*
X366207Y213099D01*
X371307D01*
X371356Y213148D01*
X372101D01*
X372827Y213874D01*
X374780D01*
X376080Y212574D01*
Y197172D01*
X374382Y195474D01*
X371882D01*
X371574Y195166D01*
X371484Y195172D01*
G03X371382Y195176I-114J-1598D01*
G01X369982D01*
G03X369968Y195175I107J-1594D01*
G02X369564Y195575I-4J400D01*
G01Y197192D01*
X369746Y197374D01*
X372382D01*
X373445Y198437D01*
Y199142D01*
G03Y202012I-1670J1435D01*
G01Y206472D01*
X372434Y207483D01*
X368767D01*
X368408Y207124D01*
Y203900D01*
G37*
G36*
G01X389840Y629169D02*
Y630728D01*
G03Y634672I-1540J1972D01*
G01Y636456D01*
X389841Y636467D01*
G03X389852Y636648I-1591J188D01*
G01Y638088D01*
X390252Y638488D01*
X396489D01*
X397533Y637444D01*
Y587103D01*
X394128Y583698D01*
G02X393561Y583700I-283J283D01*
G03X390447Y580586I-1568J-1546D01*
G02X390449Y580019I-281J-284D01*
G01X390380Y579950D01*
X386150D01*
X384769Y578569D01*
G03X384231Y578031I831J-1369D01*
G01X383900Y577700D01*
Y576203D01*
X382697Y575000D01*
X382140D01*
Y575050D01*
X375090D01*
G02X374707Y575567I0J400D01*
G03X374794Y576394I-2107J640D01*
G01X374800Y576400D01*
X376700D01*
X377500Y577200D01*
Y581500D01*
X378000Y582000D01*
X384980D01*
X385924Y582944D01*
X387626D01*
X388254Y583572D01*
X388264Y583580D01*
G03X388543Y583860I-986J1262D01*
G01X388551Y583869D01*
X388883Y584202D01*
Y587374D01*
X388996Y587429D01*
G03X389860Y588510I-696J1442D01*
G01X389873Y588566D01*
X390000Y588693D01*
Y592076D01*
G02X390606Y592418I400J-1D01*
G03X391433Y592188I827J1372D01*
G01X392833D01*
G03X394434Y593790I0J1601D01*
G01Y595190D01*
G03X392833Y596792I-1602J0D01*
G01X391433D01*
G03X390606Y596562I0J-1602D01*
G02X390000Y596904I-206J343D01*
G01Y596959D01*
X390004Y596978D01*
G03X390034Y597290I-1571J309D01*
G01Y598690D01*
G03X390004Y599002I-1601J3D01*
G01X390000Y599021D01*
Y601335D01*
G03X390002Y601400I-1599J82D01*
G01Y602800D01*
G03X390000Y602865I-1601J-17D01*
G01Y605435D01*
G03X390002Y605500I-1599J82D01*
G01Y606900D01*
G03X390000Y606965I-1601J-17D01*
G01Y607477D01*
X390408Y607885D01*
X392666D01*
X393432Y608651D01*
Y614312D01*
X392077Y615667D01*
X390694D01*
X390064Y616297D01*
Y620566D01*
X390546Y621048D01*
X392951D01*
X393600Y621697D01*
Y625735D01*
X392478Y626857D01*
X390269D01*
X389884Y627242D01*
X389887Y627329D01*
G03X389888Y627381I-1601J57D01*
G01Y628781D01*
G03X389845Y629146I-1602J-4D01*
G01X389840Y629169D01*
G37*
G36*
G01X436300Y20861D02*
X431400Y25761D01*
Y58121D01*
X437179Y63900D01*
X456800D01*
X457100Y63600D01*
Y60100D01*
X456500Y59500D01*
X438823D01*
Y59485D01*
X438149Y58811D01*
Y55269D01*
X438055Y55175D01*
X438030Y55161D01*
G03X437396Y54527I770J-1404D01*
G01X437382Y54502D01*
X436957Y54077D01*
Y41367D01*
X436184Y40593D01*
Y40428D01*
X435300Y39545D01*
Y38987D01*
X435298Y38973D01*
G03X435284Y38757I1587J-211D01*
G01Y37357D01*
G03X435298Y37141I1601J-5D01*
G01X435300Y37127D01*
Y35300D01*
X435500Y35100D01*
X440200D01*
X441300Y36200D01*
Y38900D01*
X441700Y39300D01*
X443500D01*
X443700Y39100D01*
Y22887D01*
X443698Y22873D01*
G03X443684Y22657I1587J-211D01*
G01Y21284D01*
X443292Y20892D01*
X441627D01*
X441596Y20861D01*
X436300D01*
G37*
G36*
G01X501540Y15850D02*
X500630Y16760D01*
Y23500D01*
X500929Y23798D01*
X501038D01*
X501489Y24250D01*
X508670D01*
X509240Y23680D01*
Y16680D01*
X509030D01*
X508200Y15850D01*
X501540D01*
G37*
G36*
G01X518110Y18320D02*
X517120Y19310D01*
Y27966D01*
X517327Y28173D01*
X522659D01*
X522660Y28172D01*
X523310D01*
X523865Y27617D01*
Y27585D01*
X524940Y26510D01*
X532020D01*
X532206Y26324D01*
Y21034D01*
X532221D01*
Y19511D01*
X531030Y18320D01*
X525040D01*
G03X524860I-90J-2200D01*
G01X518110D01*
G37*
G36*
G01X499906Y57094D02*
X506050Y50950D01*
Y39559D01*
X505591Y39100D01*
X499787D01*
X498763Y40124D01*
Y48237D01*
X496052Y50948D01*
X496015D01*
X495565Y51398D01*
X490800D01*
G03X490700Y51402I-114J-1597D01*
G01X489300D01*
G03X489200Y51398I14J-1601D01*
G01X487400D01*
G03X487300Y51402I-114J-1597D01*
G01X485900D01*
G03X485800Y51398I14J-1601D01*
G01X484598D01*
X483400Y50200D01*
Y45270D01*
X479830Y41700D01*
X476270D01*
X476230Y41740D01*
Y44891D01*
X476244Y44926D01*
G03X476342Y45450I-1354J524D01*
G01Y47276D01*
X478746Y49680D01*
Y53415D01*
X478751Y53436D01*
G03Y54494I-2446J529D01*
G01X478746Y54515D01*
Y55146D01*
X480250Y56650D01*
X481263D01*
X481295Y56639D01*
G03X481825Y56548I532J1511D01*
G01X483225D01*
G03X483755Y56639I-2J1602D01*
G01X483787Y56650D01*
X484663D01*
X484695Y56639D01*
G03X485225Y56548I532J1511D01*
G01X486625D01*
G03X487155Y56639I-2J1602D01*
G01X487187Y56650D01*
X487350D01*
X487526Y56826D01*
X487540Y56836D01*
G03X487939Y57235I-915J1314D01*
G01X487949Y57249D01*
X488400Y57700D01*
X496355D01*
G03X497790Y57094I1435J1396D01*
G01X499906D01*
G37*
G36*
G01X514353Y17642D02*
X510895D01*
X510460Y18077D01*
Y24220D01*
X509150Y25530D01*
X505870D01*
X505600Y25800D01*
Y29600D01*
X505900Y29900D01*
X508391D01*
X509056Y30565D01*
Y45064D01*
X509242Y45250D01*
X513584D01*
X513639Y45195D01*
Y29623D01*
X515090Y28172D01*
Y23800D01*
X515190Y23700D01*
Y18479D01*
X514353Y17642D01*
G37*
G36*
G01X533495Y22174D02*
Y42091D01*
X533674Y42270D01*
X536510D01*
X537924Y43684D01*
Y48648D01*
X538052D01*
Y50776D01*
X547488D01*
X547510Y50798D01*
X550538D01*
Y50028D01*
X554148D01*
X556008Y48168D01*
Y22494D01*
X555688Y22174D01*
X533495D01*
G37*
G36*
G01X515522Y29518D02*
X514840Y30199D01*
Y44744D01*
X515650Y45553D01*
X530136D01*
X531361Y44328D01*
X532080Y43610D01*
Y28200D01*
X531946Y28066D01*
X525936D01*
X525810Y28192D01*
Y29147D01*
X525439Y29518D01*
X515522D01*
G37*
G36*
G01X516502Y61452D02*
X501355Y76599D01*
Y79745D01*
X502865Y81255D01*
X508985D01*
X512678Y77562D01*
Y74832D01*
X514550Y72960D01*
X518332D01*
X518393Y72898D01*
X528462D01*
X531960Y69400D01*
X541625D01*
X543274Y67752D01*
Y64696D01*
X546248Y61722D01*
Y59397D01*
X547376Y58269D01*
Y54470D01*
X547380Y54466D01*
Y52367D01*
X546990Y51977D01*
X538427D01*
X538052Y52353D01*
Y54552D01*
X537843D01*
Y58235D01*
X537409Y58669D01*
X531416D01*
X528797Y61288D01*
X523315D01*
X523151Y61452D01*
X516502D01*
G37*
G36*
G01X501800Y26260D02*
X500716Y25176D01*
X500681Y25161D01*
G03X500396Y25000I641J-1468D01*
G01X497250D01*
X496600Y25650D01*
Y27500D01*
X498900Y29800D01*
Y32010D01*
G03Y32190I-2200J90D01*
G01Y36600D01*
X499493Y37193D01*
X505961D01*
Y31751D01*
X505889Y31679D01*
X504837D01*
X504350Y31192D01*
Y30750D01*
X504300Y30700D01*
Y26470D01*
X504090Y26260D01*
X501800D01*
G37*
G36*
G01X536880Y70860D02*
X536255Y71485D01*
X531945D01*
X529330Y74100D01*
X518891D01*
X518310Y74681D01*
X514909D01*
X514030Y75560D01*
Y81170D01*
X514790Y81930D01*
X536940D01*
X539640Y79230D01*
Y71260D01*
X539260Y70880D01*
X539169Y70887D01*
G03X539050Y70892I-127J-1597D01*
G01X537450D01*
G03X537152Y70863I5J-1601D01*
G01X537133Y70860D01*
X536880D01*
G37*
G36*
G01X585850Y114434D02*
X598084Y102200D01*
X598086Y102198D01*
G03X598165Y102119I1596J1517D01*
G01X598167Y102117D01*
X602744Y97540D01*
Y28456D01*
X601500Y27213D01*
X590788D01*
X585100Y32901D01*
Y78187D01*
X586107Y79193D01*
G03X586752Y80750I-1557J1557D01*
G01Y84062D01*
X585100Y85713D01*
Y89886D01*
X567800Y107186D01*
Y176908D01*
X573724Y182832D01*
Y369039D01*
X575827Y371142D01*
X587410D01*
G03X589141Y370842I1266J2158D01*
G01X589245Y370861D01*
X592596Y367510D01*
Y321210D01*
X593542Y320265D01*
Y163042D01*
X584500Y154000D01*
Y143300D01*
X585848Y141952D01*
Y119270D01*
X585850Y119268D01*
Y114434D01*
G37*
G36*
G01X903913Y760260D02*
X922094Y723897D01*
G02X922193Y723480I-834J-418D01*
G01Y3937D01*
G02X921260Y3004I-933J0D01*
G01X741409D01*
Y11000D01*
X914197D01*
Y721812D01*
X898714Y752780D01*
X891435D01*
G03X860533I-15451J-12623D01*
G01X627655D01*
G03X596812Y752853I-15451J-12623D01*
G01X596752Y752780D01*
X594593D01*
X579110Y721812D01*
Y384542D01*
X571114D01*
Y723480D01*
G02X571213Y723897I933J-1D01*
G01X589394Y760260D01*
G02X590228Y760776I835J-417D01*
G01X903079D01*
G02X903913Y760260I-1J-933D01*
G37*
G36*
G01X635989Y160041D02*
X634230Y161800D01*
X629490D01*
X628770Y162520D01*
Y170270D01*
X629100Y170600D01*
X636300D01*
X640130Y166770D01*
Y160319D01*
X639852Y160041D01*
X635989D01*
G37*
G36*
G01X641100Y145400D02*
X629800D01*
X628600Y146600D01*
Y157100D01*
X630300Y158800D01*
X641700D01*
X642700Y157800D01*
Y147000D01*
X641100Y145400D01*
G37*
G36*
G01X693900Y414000D02*
X701850Y406050D01*
X722250D01*
X739650Y388650D01*
Y369450D01*
X742600Y366500D01*
Y361200D01*
X739700Y358300D01*
X739406D01*
X739386Y358304D01*
G03X739065Y358336I-319J-1569D01*
G01X737665D01*
G03X737481Y358326I-5J-1601D01*
G01X737385Y358315D01*
X737100Y358600D01*
Y363700D01*
X736000Y364800D01*
X732061D01*
X732033Y364808D01*
G03X730767I-633J-2108D01*
G01X730739Y364800D01*
X729100D01*
X728400Y364100D01*
Y358870D01*
X727931Y358402D01*
X726500D01*
G03X726435Y358400I17J-1601D01*
G01X724900D01*
X724000Y357500D01*
Y356500D01*
X723985Y356485D01*
Y348985D01*
X723700Y348700D01*
X720800D01*
X720400Y349100D01*
Y357441D01*
G03Y360519I-1973J1539D01*
G01Y362237D01*
X720408Y362265D01*
G03X720412Y362278I-2102J654D01*
G01X720427Y362327D01*
X720700Y362600D01*
Y364300D01*
X719500Y365500D01*
X715900D01*
X714900Y364500D01*
Y358600D01*
X672900D01*
X672600Y358300D01*
X667858D01*
X664379Y361779D01*
Y407785D01*
X664393Y407820D01*
G03X664502Y408400I-1493J581D01*
G01Y410400D01*
G03X664393Y410980I-1602J-1D01*
G01X664379Y411015D01*
Y411885D01*
X664393Y411920D01*
G03X664502Y412500I-1493J581D01*
G01Y414500D01*
G03X664393Y415080I-1602J-1D01*
G01X664379Y415115D01*
Y415985D01*
X664393Y416020D01*
G03X664502Y416600I-1493J581D01*
G01Y418600D01*
G03X664393Y419180I-1602J-1D01*
G01X664379Y419215D01*
Y420085D01*
X664393Y420120D01*
G03X664502Y420700I-1493J581D01*
G01Y422700D01*
G03X664393Y423280I-1602J-1D01*
G01X664379Y423315D01*
Y424185D01*
X664393Y424220D01*
G03X664502Y424800I-1493J581D01*
G01Y426800D01*
G03X664393Y427380I-1602J-1D01*
G01X664379Y427415D01*
Y428285D01*
X664393Y428320D01*
G03X664502Y428900I-1493J581D01*
G01Y430900D01*
G03X664419Y431406I-1602J-3D01*
G01X664380Y431523D01*
X664900Y432043D01*
Y441800D01*
X664480Y442220D01*
X664491Y442316D01*
G03X664502Y442500I-1591J187D01*
G01Y443900D01*
G03X664411Y444430I-1602J-2D01*
G01X664400Y444462D01*
Y460000D01*
X665100Y460700D01*
X669200D01*
X669600Y461100D01*
X676800D01*
X677500Y460400D01*
X678335D01*
G03X678400Y460398I82J1599D01*
G01X680000D01*
G03X680065Y460400I-17J1601D01*
G01X681300D01*
X683600Y458100D01*
X689637D01*
X689665Y458092D01*
G03X690935I635J2108D01*
G01X690963Y458100D01*
X693400D01*
X693691Y458391D01*
X698550D01*
X698857Y458084D01*
Y455800D01*
X697600Y454543D01*
Y434500D01*
X693900Y430800D01*
Y414000D01*
G37*
G36*
G01X655163Y406553D02*
X654100Y407616D01*
Y443600D01*
X655200Y444700D01*
X662700D01*
X663198Y444202D01*
Y441802D01*
X663200Y441801D01*
Y441300D01*
X662400Y440500D01*
Y432100D01*
X663178Y431322D01*
Y407562D01*
X662169Y406553D01*
X655163D01*
G37*
G36*
G01X645500Y471900D02*
X652100Y465300D01*
Y447700D01*
X651600Y447200D01*
X631400D01*
X618800Y459800D01*
Y465190D01*
X619108Y465497D01*
Y484144D01*
X618800Y484451D01*
Y498375D01*
X619409Y498984D01*
X641216D01*
X645500Y494700D01*
Y471900D01*
G37*
G36*
G01X608326Y465768D02*
X605027Y469067D01*
Y483251D01*
X606686Y484910D01*
X616642D01*
X617906Y483646D01*
Y467955D01*
X617905Y467946D01*
G03X617898Y467800I1595J-150D01*
G01Y466200D01*
G03X617906Y466045I1602J5D01*
G01Y465995D01*
X617679Y465768D01*
X608326D01*
G37*
G36*
G01X643900Y508000D02*
X642900Y509000D01*
Y526000D01*
X644250Y527350D01*
X647548D01*
Y527348D01*
X663752D01*
X666400Y524700D01*
Y509900D01*
X664500Y508000D01*
X643900D01*
G37*
G36*
G01X608160Y525543D02*
X607160Y526543D01*
Y535543D01*
X608717Y537100D01*
X617716D01*
X617758Y537142D01*
X617942Y537326D01*
X621104D01*
G03X622120Y537662I1J1701D01*
G01X622174Y537702D01*
X622429D01*
X622658Y537471D01*
Y534298D01*
X613903Y525543D01*
X608160D01*
G37*
G36*
G01X640892Y524144D02*
X639460D01*
G03X639274Y524134I-7J-1601D01*
G01X639178Y524122D01*
X638800Y524500D01*
X634900D01*
X629500Y529900D01*
Y533400D01*
X629507D01*
Y533542D01*
X630264D01*
Y533288D01*
X630725D01*
Y533275D01*
X636000Y528000D01*
X639500D01*
X641300Y526200D01*
Y524544D01*
G02X640892Y524144I-400J0D01*
G37*
G36*
G01X612512Y522395D02*
X618660Y528543D01*
X621600D01*
X623400Y530343D01*
Y533288D01*
X624056D01*
Y533542D01*
X628700D01*
Y529600D01*
X628800Y529500D01*
Y529403D01*
X631660Y526543D01*
Y519543D01*
X634052Y517152D01*
X637200Y514004D01*
Y506089D01*
X636554Y505443D01*
X614771D01*
X614160Y506054D01*
Y513740D01*
X612500Y515400D01*
Y520551D01*
X612501Y520562D01*
G03X612512Y520743I-1591J188D01*
G01Y522395D01*
G37*
G36*
G01X630161Y534731D02*
X624168D01*
Y541345D01*
X630161D01*
Y534731D01*
G37*
G36*
G01X663265Y546200D02*
X656300D01*
X654666Y547834D01*
Y561927D01*
X655299Y562560D01*
X664099D01*
X664629Y562030D01*
Y547564D01*
X663265Y546200D01*
G37*
G36*
G01X640302Y537402D02*
X641203Y536500D01*
X654700D01*
X655900Y537700D01*
Y541300D01*
X657643Y543043D01*
X663660D01*
X664660Y542043D01*
Y529543D01*
X663668Y528552D01*
X646498D01*
X646475Y528557D01*
G03X646100Y528602I-377J-1557D01*
G01X644500D01*
G03X644125Y528557I2J-1602D01*
G01X644102Y528552D01*
X643752D01*
X643744Y528543D01*
X637160D01*
X632002Y533702D01*
Y534098D01*
X631662Y534438D01*
Y537002D01*
X631886Y537226D01*
X636873D01*
X637050Y537402D01*
X640302D01*
G37*
G36*
G01X662252Y631752D02*
X647852D01*
X639600Y640005D01*
Y694900D01*
X654300Y709600D01*
X663300D01*
X665200Y707700D01*
Y634700D01*
X662252Y631752D01*
G37*
G36*
G01X672000Y627900D02*
X666844Y633056D01*
Y674103D01*
X666817Y674130D01*
Y707604D01*
X667712Y708498D01*
X667801D01*
G03X669162Y708483I698J1552D01*
G01X669200Y708498D01*
X670202D01*
Y708704D01*
X685801D01*
X697988Y696517D01*
Y633204D01*
X692684Y627900D01*
X672000D01*
G37*
G36*
G01X743500Y473800D02*
X737800Y468100D01*
Y454300D01*
X738200Y453900D01*
X742000D01*
X742200Y453700D01*
Y427300D01*
X740400Y425500D01*
X730400D01*
X726655Y429245D01*
Y468675D01*
X725526Y469804D01*
X725214D01*
X725113Y469904D01*
X724351D01*
X723636Y470619D01*
Y473483D01*
X725473Y475320D01*
X730977D01*
X731607Y475950D01*
X733505D01*
X733805Y476250D01*
X743450D01*
X743500Y476200D01*
Y473800D01*
G37*
G36*
G01X732558Y478600D02*
X730479Y476521D01*
X730095D01*
X730054Y476541D01*
G03X729359Y476700I-696J-1443D01*
G01X727759D01*
G03X727064Y476541I1J-1602D01*
G01X727023Y476521D01*
X724975D01*
X722179Y473725D01*
Y470377D01*
X723853Y468703D01*
X724486D01*
X724523Y468688D01*
G03X724651Y468639I851J2031D01*
G01X724695Y468624D01*
X725044Y468276D01*
Y419436D01*
X724251Y418643D01*
X716950D01*
X716000Y419593D01*
Y441100D01*
X712500Y444600D01*
Y473105D01*
X716906Y477511D01*
X716908Y477513D01*
G03X716987Y477592I-1517J1596D01*
G01X716989Y477594D01*
X719395Y480000D01*
X728400D01*
X728600Y480200D01*
X732585D01*
X732644Y480140D01*
X748500D01*
Y478606D01*
X743778D01*
Y478600D01*
X732558D01*
G37*
G36*
G01X711078Y432382D02*
X713308Y430151D01*
Y412891D01*
X711986Y411569D01*
X710735D01*
G03X707277I-1729J-1363D01*
G01X699199D01*
X696678Y414090D01*
Y430747D01*
X698832Y432901D01*
X710559D01*
X711078Y432382D01*
G37*
G36*
G01X696189Y516520D02*
X688378D01*
X686972Y517926D01*
Y530104D01*
X688823Y531955D01*
X697188D01*
X699500Y529643D01*
Y519831D01*
X696189Y516520D01*
G37*
G36*
G01X678200Y531600D02*
X671500D01*
X668676Y534424D01*
Y569113D01*
X669960Y570397D01*
X677731D01*
X677986Y570142D01*
X678000D01*
Y564000D01*
X679300Y562700D01*
Y532700D01*
X678200Y531600D01*
G37*
G36*
G01X702348Y570929D02*
Y571358D01*
X700379D01*
X689600D01*
Y572400D01*
X689500Y572500D01*
X688500D01*
X688400Y572600D01*
Y573000D01*
X686100Y575300D01*
X681600D01*
X681000Y575900D01*
Y582600D01*
X682300Y583900D01*
X684200D01*
X684224Y583876D01*
X688124D01*
X688176Y583929D01*
X688901D01*
Y583840D01*
X700379D01*
X702348D01*
Y583929D01*
X716176D01*
X718176Y581929D01*
Y572929D01*
X716176Y570929D01*
X712190D01*
Y571358D01*
X708588D01*
Y570929D01*
X702348D01*
G37*
G36*
G01X723271Y553929D02*
X722500Y554700D01*
Y559835D01*
G03X722502Y559900I-1599J82D01*
G01Y561300D01*
G03X722500Y561365I-1601J-17D01*
G01Y563835D01*
G03X722502Y563900I-1599J82D01*
G01Y565300D01*
G03X722500Y565365I-1601J-17D01*
G01Y566200D01*
X721800Y566900D01*
X721400D01*
X720800Y567500D01*
Y567838D01*
X720811Y567870D01*
G03X720902Y568400I-1511J532D01*
G01Y569800D01*
G03X720866Y570136I-1602J-2D01*
G01X720843Y570243D01*
X721100Y570500D01*
X721176D01*
Y574598D01*
X721202D01*
Y578002D01*
X721176D01*
Y580929D01*
X721676Y581429D01*
X730676D01*
X731176Y580929D01*
Y554429D01*
X730676Y553929D01*
X723271D01*
G37*
G36*
G01X689900Y585350D02*
Y585900D01*
X687300Y588500D01*
X677306D01*
X677287Y588503D01*
G03X676994Y588530I-293J-1574D01*
G01X675394D01*
G03X675101Y588503I0J-1601D01*
G01X675082Y588500D01*
X674812D01*
X672912Y590400D01*
Y606300D01*
X673112Y606500D01*
X700700D01*
X701288Y605912D01*
Y597930D01*
G03Y596198I1227J-866D01*
G01Y585615D01*
X701024Y585350D01*
X689900D01*
G37*
G36*
G01X682500Y533300D02*
X682176Y533624D01*
Y563124D01*
X680600Y564700D01*
Y570100D01*
X680900Y570400D01*
X687029D01*
X687500Y569929D01*
X688394D01*
Y569848D01*
X699758D01*
X700676Y568929D01*
Y560334D01*
X700656Y560293D01*
G03X700498Y559600I1444J-694D01*
G01Y557000D01*
G03X700656Y556307I1602J1D01*
G01X700676Y556266D01*
Y537776D01*
X696200Y533300D01*
X682500D01*
G37*
G36*
G01X764360Y115550D02*
X763990Y115920D01*
Y122510D01*
X761530Y124970D01*
X757080D01*
X756675Y125375D01*
Y129255D01*
X758260Y130840D01*
X771110D01*
X771710Y130240D01*
Y117530D01*
X769730Y115550D01*
X764360D01*
G37*
G36*
G01X758200Y110900D02*
X749400D01*
X748300Y112000D01*
Y127500D01*
X749900Y129100D01*
X754700D01*
X755400Y128400D01*
Y124800D01*
X756500Y123700D01*
X758000D01*
X759600Y122100D01*
Y112300D01*
X758200Y110900D01*
G37*
G36*
G01X806400Y169700D02*
X798700Y177400D01*
X787000D01*
X783900Y180500D01*
Y188800D01*
X784620Y189520D01*
X784716Y189509D01*
G03X784900Y189498I187J1591D01*
G01X786300D01*
G03X786598Y189527I-5J1601D01*
G01X786617Y189530D01*
X789583D01*
X789602Y189527D01*
G03X789900Y189498I303J1572D01*
G01X791300D01*
G03X791598Y189527I-5J1601D01*
G01X791617Y189530D01*
X794583D01*
X794602Y189527D01*
G03X794900Y189498I303J1572D01*
G01X796300D01*
G03X796598Y189527I-5J1601D01*
G01X796617Y189530D01*
X799583D01*
X799602Y189527D01*
G03X799900Y189498I303J1572D01*
G01X801300D01*
G03X801598Y189527I-5J1601D01*
G01X801617Y189530D01*
X804583D01*
X804602Y189527D01*
G03X804900Y189498I303J1572D01*
G01X806300D01*
G03X806598Y189527I-5J1601D01*
G01X806617Y189530D01*
X809583D01*
X809602Y189527D01*
G03X809900Y189498I303J1572D01*
G01X811300D01*
G03X811598Y189527I-5J1601D01*
G01X811617Y189530D01*
X811970D01*
X812200Y189300D01*
Y176200D01*
X813900Y174500D01*
Y171000D01*
X812600Y169700D01*
X806400D01*
G37*
G36*
G01X795720Y252430D02*
X798530Y249620D01*
X798544Y249570D01*
G03X799160Y248721I1447J402D01*
G01Y247710D01*
X796020Y244570D01*
X794990D01*
X794440Y245120D01*
Y246173D01*
X794442Y246174D01*
Y246330D01*
X795333Y247222D01*
X795508Y247242D01*
X795512Y247245D01*
X795565Y247259D01*
G03X796060Y249335I-290J1166D01*
G01Y249670D01*
X794550Y251180D01*
Y252150D01*
X794830Y252430D01*
X795720D01*
G37*
G36*
G01X748400Y403400D02*
X746300Y405500D01*
Y415600D01*
X748200Y417500D01*
X785238D01*
X785270Y417489D01*
G03X785800Y417398I532J1511D01*
G01X787400D01*
G03X787930Y417489I-2J1602D01*
G01X787962Y417500D01*
X789635D01*
G03X789700Y417498I82J1599D01*
G01X791100D01*
G03X791165Y417500I-17J1601D01*
G01X795600D01*
X796200Y416900D01*
Y405300D01*
X794300Y403400D01*
X748400D01*
G37*
G36*
G01X773700Y447300D02*
X773200Y447800D01*
Y460400D01*
X775700Y462900D01*
X835800D01*
X838500Y460200D01*
Y447300D01*
X837600Y446400D01*
X795300D01*
X794400Y447300D01*
X773700D01*
G37*
G36*
G01X739400Y467700D02*
X744200Y472500D01*
Y478000D01*
X744298Y478098D01*
X749002D01*
Y478150D01*
X753750D01*
X753900Y478000D01*
Y476700D01*
X755000Y475600D01*
X767000D01*
X768100Y474500D01*
Y456000D01*
X766200Y454100D01*
X748900D01*
X747800Y455200D01*
Y459900D01*
X746652Y461048D01*
Y461132D01*
X746568D01*
X746200Y461500D01*
X739800D01*
X739400Y461900D01*
Y467700D01*
G37*
G36*
G01X796199Y418600D02*
X796098Y418702D01*
X747798D01*
X746500Y420000D01*
Y444900D01*
X747625Y446025D01*
X793625D01*
X794950Y444700D01*
X831500D01*
X839100Y437100D01*
Y421800D01*
X835900Y418600D01*
X796199D01*
G37*
G36*
G01X803772Y493451D02*
Y496634D01*
X803066D01*
X803050Y496650D01*
X797300D01*
X797050Y496900D01*
X796902D01*
Y498400D01*
G03X795300Y500002I-1602J0D01*
G01X793700D01*
G03X793300Y499951I1J-1602D01*
G02X792800Y500338I-100J387D01*
G01Y505399D01*
X793601Y506200D01*
X796300D01*
X796800Y505700D01*
Y503900D01*
X797170Y503530D01*
Y503066D01*
X797634D01*
X797700Y503000D01*
X803800D01*
X803900Y503100D01*
Y506291D01*
X815860D01*
X816198Y505952D01*
Y504302D01*
X816600Y503901D01*
Y503300D01*
X816656Y503244D01*
Y503066D01*
X823258D01*
Y503098D01*
X827998D01*
X827999Y503100D01*
X840700D01*
X841700Y502100D01*
Y494900D01*
X840850Y494050D01*
X826050D01*
X823500Y496600D01*
X823258D01*
Y496634D01*
X816656D01*
Y493556D01*
X816551Y493451D01*
X803772D01*
G37*
G36*
G01X800208Y471000D02*
X798218Y472990D01*
Y491487D01*
X798931Y492200D01*
X805500D01*
X805700Y492000D01*
Y486400D01*
X805954Y486146D01*
Y486008D01*
X806950Y485012D01*
Y471250D01*
X806700Y471000D01*
X800208D01*
G37*
G36*
G01X876650Y389850D02*
X861850D01*
X861250Y390450D01*
Y396650D01*
X864000Y399400D01*
X876350D01*
X877142Y398608D01*
Y390342D01*
X876650Y389850D01*
G37*
G36*
G01X818799Y356563D02*
X817678Y357684D01*
Y373597D01*
X817609Y373666D01*
Y378609D01*
X819400Y380400D01*
X851604D01*
G03X851796I96J2500D01*
G01X857100D01*
X863734Y387034D01*
X885540D01*
G03X887540I1000J1962D01*
G01X894715D01*
X896864Y384885D01*
Y359064D01*
X894363Y356563D01*
X818799D01*
G37*
G36*
G01X851000Y460900D02*
X841000D01*
X840200Y461700D01*
Y471800D01*
X841100Y472700D01*
X851000D01*
X851700Y472000D01*
Y461600D01*
X851000Y460900D01*
G37*
G36*
G01X840000Y474000D02*
Y474635D01*
G03X840002Y474700I-1599J82D01*
G01Y476300D01*
G03X840000Y476365I-1601J-17D01*
G01Y484800D01*
X850400D01*
X851400Y483800D01*
Y475400D01*
X850000Y474000D01*
X840000D01*
G37*
G36*
G01X823258Y504300D02*
Y504310D01*
X817890D01*
X817816Y504384D01*
Y507452D01*
X816398D01*
X816300Y507550D01*
X809556D01*
Y512894D01*
X809500D01*
Y521672D01*
X810102Y522273D01*
Y522502D01*
X810300Y522700D01*
X832800D01*
X834000Y521500D01*
Y510800D01*
X827500Y504300D01*
X827149D01*
G03X827084Y504302I-82J-1599D01*
G01X825484D01*
G03X825419Y504300I17J-1601D01*
G01X823258D01*
G37*
G36*
G01X822900Y493800D02*
X823900Y492800D01*
X837500D01*
X838900Y491400D01*
Y486002D01*
X838798D01*
Y472798D01*
X838900D01*
Y466900D01*
X838200Y466200D01*
X821400D01*
X817300Y470300D01*
X808800D01*
X808300Y470800D01*
Y476335D01*
G03X808302Y476400I-1599J82D01*
G01Y478000D01*
G03X808301Y478017I-1597J-85D01*
G01Y478101D01*
X808500Y478300D01*
X810600D01*
X811800Y479500D01*
Y486000D01*
X809556Y488244D01*
Y492200D01*
X817600D01*
X817648Y492248D01*
X817816D01*
Y493016D01*
X817902Y493102D01*
Y495390D01*
X822510D01*
X822900Y495000D01*
Y493800D01*
G37*
G36*
G01X882497Y388663D02*
X878578D01*
X878547Y388694D01*
Y401275D01*
X880190Y402918D01*
X896342D01*
X896531Y402729D01*
Y393025D01*
X896373Y392867D01*
X886701D01*
X882497Y388663D01*
G37*
%LPC*%
G75*
G36*
G01X59003Y27363D02*
G03X59692Y27639I289J276D01*
G01Y30675D01*
G02Y38223I1332J3774D01*
G01Y40808D01*
X62296D01*
Y38244D01*
G02Y30654I-1272J-3795D01*
G01Y13904D01*
X59692D01*
Y21573D01*
G03X59003Y21849I-400J0D01*
G02Y27363I-2901J2757D01*
G37*
G36*
G01X678400Y458400D02*
Y457600D01*
X677600D01*
X677274Y457179D01*
X676474D01*
Y457979D01*
X677274D01*
X677600Y458400D01*
X678400D01*
G37*
G36*
G01X693391Y405674D02*
G03X693396Y405390I143J-140D01*
G02X690295Y405336I-1523J-1590D01*
G03X690290Y405620I-143J140D01*
G02X690222Y408732I1523J1590D01*
G03X690231Y409275I-289J276D01*
G02X693465Y409219I1643J1466D01*
G03X693456Y408676I289J-276D01*
G02X693391Y405674I-1643J-1466D01*
G37*
G54D159*
X339331Y91929D03*
G54D161*
X596300Y66950D03*
X597950Y58950D03*
X721504Y402321D03*
G54D160*
X346457Y84567D03*
G54D158*
X47244Y15406D03*
G54D157*
X78470Y59560D03*
X56910Y53610D03*
X59110D03*
X78470Y53960D03*
X80670D03*
X56910Y48010D03*
X59110D03*
X79968Y505366D03*
X82168D03*
X74273Y505379D03*
X76473D03*
X68800Y505500D03*
X71000D03*
X85573D03*
X32165Y531538D03*
Y533738D03*
X32158Y537154D03*
Y539354D03*
X32258Y542781D03*
Y544981D03*
X32000Y548400D03*
Y550600D03*
X32187Y554053D03*
Y556253D03*
X60354Y638850D03*
Y641050D03*
X60084Y642700D03*
Y645100D03*
X60246Y646750D03*
Y648950D03*
X84300Y637500D03*
X86700D03*
X65954Y638850D03*
Y641050D03*
X66084Y642700D03*
X80584Y666700D03*
X82984D03*
X51100Y670184D03*
X80584Y672700D03*
X82984D03*
X85650Y725450D03*
Y719950D03*
X136549Y686615D03*
Y688815D03*
X120449Y690247D03*
X122649D03*
X112249Y692547D03*
X114449D03*
X116349D03*
X118549D03*
X147849Y741215D03*
Y738815D03*
X97750Y719950D03*
Y725450D03*
X157821Y515692D03*
X159627Y515722D03*
X146700Y638400D03*
X148900D03*
X148200Y643900D03*
X184176Y637368D03*
X186376D03*
X188276D03*
X190476D03*
X192376D03*
X174100Y638100D03*
X178200D03*
X224200Y711800D03*
X226600D03*
X224200Y717800D03*
X226600D03*
X349950Y102950D03*
X354450D03*
X340900Y188674D03*
Y191074D03*
X341129Y192578D03*
Y194778D03*
X320900Y640500D03*
X323300D03*
X320900Y646500D03*
X300870Y611150D03*
Y613550D03*
X300900Y615284D03*
Y617484D03*
X300948Y619377D03*
Y621577D03*
X316400Y611600D03*
X318800D03*
X306870Y613550D03*
X306500Y615284D03*
X310504Y710920D03*
X312904D03*
X310504Y716920D03*
X290218Y683053D03*
Y685253D03*
X290004Y686920D03*
Y689320D03*
X290282Y690847D03*
Y693047D03*
X295818Y683053D03*
X313720Y683720D03*
X316120D03*
X295818Y685253D03*
X296004Y686920D03*
X357550Y108450D03*
X362050D03*
X367500Y109300D03*
Y112700D03*
Y114300D03*
Y117700D03*
Y119300D03*
Y122700D03*
X346900Y191074D03*
X346729Y192578D03*
X379450Y580306D03*
X381450D03*
X383650D03*
X391079Y586643D03*
X392100Y588471D03*
Y590671D03*
X391033Y598990D03*
X393233D03*
X392200Y601000D03*
Y603200D03*
Y605100D03*
X392236Y618601D03*
X392086Y629181D03*
X392050Y636248D03*
X441485Y23057D03*
X441585Y25057D03*
Y27257D03*
Y29357D03*
Y31557D03*
X441335Y33157D03*
X433085Y36957D03*
Y39157D03*
X432800Y40957D03*
Y44357D03*
Y45857D03*
Y49257D03*
Y50757D03*
Y54157D03*
X435981Y55847D03*
Y58047D03*
X504322Y20693D03*
X505622D03*
X532240Y65910D03*
X535640D03*
X537050Y67290D03*
X539450D03*
X500922Y29693D03*
X537050Y73290D03*
X532240Y74910D03*
X535640D03*
X637940Y162210D03*
X640140Y156610D03*
X637940D03*
X721400Y350800D03*
X739465Y360535D03*
X726100Y360600D03*
X712400Y360700D03*
X666900Y408000D03*
Y410800D03*
Y412100D03*
Y414900D03*
Y416200D03*
Y419000D03*
Y420300D03*
Y423100D03*
Y424400D03*
Y427200D03*
Y428500D03*
Y431300D03*
X666700Y442100D03*
Y444300D03*
X695427Y456206D03*
X697627D03*
X673474Y457579D03*
X680400Y458000D03*
X660900Y408000D03*
Y410800D03*
Y412100D03*
Y414900D03*
Y416200D03*
Y419000D03*
Y420300D03*
Y423100D03*
Y424400D03*
Y427200D03*
Y428500D03*
Y431300D03*
X661100Y442100D03*
X621500Y465800D03*
Y468200D03*
X615500D03*
X644100Y525000D03*
X646500D03*
X610800Y533300D03*
X614200D03*
X639060Y526343D03*
X628160Y519843D03*
X614910Y520343D03*
Y522743D03*
X628160Y523243D03*
X644100Y531000D03*
X646500D03*
X727359Y473098D03*
X729759D03*
X727359Y479098D03*
X729759D03*
X694750Y527250D03*
X689250D03*
X724700Y559500D03*
Y561700D03*
Y563500D03*
Y565700D03*
X723100Y568000D03*
Y570200D03*
X726900Y579150D03*
X729100D03*
X674994Y590929D03*
X677394D03*
X689250Y534850D03*
X694750D03*
X689250Y539350D03*
X694750D03*
X758820Y127610D03*
X753220Y125410D03*
Y127610D03*
X786700Y187300D03*
X789500D03*
X791700D03*
X794500D03*
X796700D03*
X799500D03*
X801700D03*
X804500D03*
X806700D03*
X809500D03*
X780800Y413500D03*
X784200D03*
X785400Y415000D03*
X787800D03*
X789300Y415300D03*
X791500D03*
X760700Y471400D03*
X764100D03*
X789300Y420900D03*
X791500D03*
X785400Y421000D03*
X787800D03*
X780800Y422500D03*
X784200D03*
X825084Y500700D03*
X827484D03*
X795700Y502400D03*
X804800Y472400D03*
Y474600D03*
X804700Y476000D03*
Y478400D03*
X804834Y479800D03*
Y482000D03*
X878523Y383117D03*
X881923D03*
X842400Y476700D03*
X825084Y506700D03*
X827484D03*
X810400Y472400D03*
X836400Y474300D03*
X810400Y474600D03*
X810700Y476000D03*
X836400Y476700D03*
X881923Y392117D03*
%LPD*%
G75*
G54D100*
X457950Y28510D03*
Y42290D03*
X478050D03*
Y28510D03*
G54D110*
X542550Y54803D03*
Y48397D03*
G54D101*
X458250Y30479D03*
Y32447D03*
Y34416D03*
Y36384D03*
Y38353D03*
Y40321D03*
X477750D03*
Y38353D03*
Y36384D03*
Y34416D03*
Y32447D03*
Y30479D03*
G54D120*
X625100Y494326D03*
Y510074D03*
G54D102*
X468000Y35400D03*
G54D111*
X564803Y24409D03*
X574803D03*
X584803D03*
X753780D03*
X763780D03*
X773780D03*
X801024D03*
X811024D03*
X821024D03*
G54D112*
X576160Y54765D03*
X573600D03*
X571040D03*
Y62835D03*
X573600D03*
X576160D03*
X765260Y50010D03*
X762700D03*
X760140D03*
Y58080D03*
X762700D03*
X765260D03*
G54D130*
X700546Y577599D03*
G54D121*
X617250Y555400D03*
X721150Y576300D03*
G54D10*
X8500Y18279D03*
Y28279D03*
Y38279D03*
Y48279D03*
Y58279D03*
Y68279D03*
X13721Y8500D03*
X8500Y13279D03*
Y23279D03*
Y33279D03*
Y43279D03*
Y53279D03*
Y63279D03*
Y78279D03*
Y88279D03*
Y98279D03*
Y108279D03*
Y118279D03*
Y128279D03*
Y73279D03*
Y83279D03*
Y93279D03*
Y103279D03*
Y113279D03*
Y123279D03*
Y133279D03*
Y138279D03*
Y148279D03*
Y158279D03*
Y168279D03*
Y178279D03*
Y188279D03*
Y198279D03*
Y143279D03*
Y153279D03*
Y163279D03*
Y173279D03*
Y183279D03*
Y193279D03*
Y208279D03*
Y218279D03*
Y228279D03*
Y238279D03*
Y248279D03*
Y258279D03*
Y203279D03*
Y213279D03*
Y223279D03*
Y233279D03*
Y243279D03*
Y253279D03*
Y263279D03*
Y268279D03*
Y278279D03*
Y288279D03*
Y298279D03*
Y308279D03*
Y318279D03*
Y328279D03*
Y273279D03*
Y283279D03*
Y293279D03*
Y303279D03*
Y313279D03*
Y323279D03*
Y338279D03*
Y348279D03*
Y358279D03*
Y368279D03*
Y378279D03*
Y388279D03*
Y333279D03*
Y343279D03*
Y353279D03*
Y363279D03*
Y373279D03*
Y383279D03*
Y393279D03*
Y398279D03*
Y408279D03*
Y418279D03*
Y428279D03*
Y438279D03*
Y448279D03*
Y458279D03*
Y403279D03*
Y413279D03*
Y423279D03*
Y433279D03*
Y443279D03*
Y453279D03*
Y468279D03*
Y478279D03*
Y488279D03*
Y498279D03*
Y508279D03*
Y518279D03*
Y528279D03*
Y463279D03*
Y473279D03*
Y483279D03*
Y493279D03*
Y503279D03*
Y513279D03*
Y523279D03*
Y538279D03*
Y548279D03*
Y558279D03*
Y568279D03*
Y578279D03*
Y588279D03*
Y533279D03*
Y543279D03*
Y553279D03*
Y563279D03*
Y573279D03*
Y583279D03*
Y593279D03*
Y598279D03*
Y608279D03*
Y618279D03*
Y628279D03*
Y638279D03*
Y648279D03*
Y658279D03*
Y603279D03*
Y613279D03*
Y623279D03*
Y633279D03*
Y643279D03*
Y653279D03*
Y668279D03*
Y678279D03*
Y688279D03*
Y698279D03*
Y708279D03*
Y718279D03*
Y663279D03*
Y673279D03*
Y683279D03*
Y693279D03*
Y703279D03*
Y713279D03*
X8892Y723187D03*
X11090Y727806D03*
X13500Y732400D03*
X78721Y8500D03*
X68721D03*
X58721D03*
X48721D03*
X38721D03*
X28721D03*
X18721D03*
X73721D03*
X53721D03*
X43721D03*
X33721D03*
X23721D03*
X63721D03*
X75534Y625175D03*
X75300Y679300D03*
Y674300D03*
X78370Y724300D03*
Y719500D03*
X28100Y755600D03*
X33100D03*
X69057Y755280D03*
X74057D03*
X20300Y746200D03*
X15800Y736900D03*
X18100Y741500D03*
X22600Y750800D03*
X79057Y755280D03*
X108721Y8500D03*
X98721D03*
X88721D03*
X112197Y65406D03*
Y60406D03*
Y55406D03*
X103721Y8500D03*
X93721D03*
X83721D03*
X112197Y75406D03*
Y85406D03*
Y95406D03*
Y105406D03*
Y115406D03*
Y120406D03*
Y110406D03*
Y100406D03*
Y90406D03*
Y80406D03*
Y70406D03*
Y145406D03*
Y195406D03*
Y185406D03*
Y175406D03*
Y165406D03*
Y155406D03*
Y200406D03*
Y190406D03*
Y180406D03*
Y170406D03*
Y160406D03*
Y150406D03*
Y265406D03*
Y255406D03*
Y245406D03*
Y235406D03*
Y225406D03*
Y215406D03*
Y205406D03*
Y260406D03*
Y250406D03*
Y240406D03*
Y230406D03*
Y220406D03*
Y210406D03*
Y325406D03*
Y315406D03*
Y305406D03*
Y295406D03*
Y285406D03*
Y275406D03*
Y330406D03*
Y320406D03*
Y310406D03*
Y300406D03*
Y290406D03*
Y280406D03*
Y270406D03*
Y390406D03*
Y380406D03*
Y370406D03*
Y360406D03*
Y350406D03*
Y395406D03*
Y385406D03*
Y375406D03*
Y365406D03*
Y355406D03*
Y345406D03*
Y335406D03*
Y340406D03*
Y420406D03*
Y410406D03*
Y400406D03*
Y425406D03*
Y415406D03*
Y405406D03*
X140500Y620300D03*
X103600Y637800D03*
X103500Y645500D03*
Y650535D03*
X80334Y625175D03*
X99600Y673500D03*
Y678500D03*
X86500Y703100D03*
X86600Y708300D03*
X96800Y662000D03*
X90200Y667100D03*
X85400D03*
X99600Y683500D03*
X81300Y675100D03*
Y680100D03*
X134223Y691027D03*
X83170Y724300D03*
Y719500D03*
X122435Y666782D03*
Y661982D03*
X144057Y755280D03*
X134057D03*
X124057D03*
X114057D03*
X104057D03*
X94057D03*
X84057D03*
X89057D03*
X99057D03*
X109057D03*
X119057D03*
X129057D03*
X139057D03*
X91700Y744800D03*
X96500D03*
X101300D03*
X106100D03*
X110900D03*
X115700D03*
X120500D03*
X125300D03*
X208000Y520500D03*
X208100Y515200D03*
X202800Y509900D03*
X174100Y628900D03*
X168800Y628400D03*
X159200Y623240D03*
X164130Y625550D03*
X168300Y621900D03*
X158350Y629040D03*
X181540Y644450D03*
X208300Y704985D03*
X203500D03*
X198700D03*
X193900D03*
X155400Y717700D03*
X204057Y755280D03*
X194057D03*
X184057D03*
X174057D03*
X164057D03*
X154057D03*
X149057D03*
X159057D03*
X169057D03*
X179057D03*
X189057D03*
X199057D03*
X209057D03*
X217100Y520300D03*
X238200Y524600D03*
X235562Y541096D03*
X249998Y550219D03*
X246800Y541900D03*
X241100Y541600D03*
X240900Y547300D03*
X235500Y548200D03*
X226168Y618952D03*
X235600Y611800D03*
X222700Y704985D03*
X217900D03*
X213100D03*
X249500Y719500D03*
Y724300D03*
X274057Y755280D03*
X264057D03*
X254057D03*
X244057D03*
X234057D03*
X224057D03*
X214057D03*
X219057D03*
X229057D03*
X239057D03*
X249057D03*
X259057D03*
X269057D03*
X249500Y729100D03*
Y733900D03*
Y738700D03*
X315120Y8500D03*
X310120D03*
X305120D03*
X300120D03*
X296020Y9420D03*
Y14420D03*
Y19420D03*
Y24420D03*
Y29420D03*
X321382Y197574D03*
X296282Y189224D03*
Y184424D03*
X301082D03*
Y189224D03*
X335132Y195874D03*
X305862Y210014D03*
X334882Y215874D03*
Y220874D03*
X321382Y202374D03*
X335132Y205974D03*
X335200Y640100D03*
X330400D03*
X335000Y615400D03*
X335300Y609800D03*
X335000Y621200D03*
X325600Y640100D03*
X322586Y653754D03*
X317786D03*
X312986D03*
X308186D03*
X330200Y709300D03*
X334650Y689700D03*
X335350Y684650D03*
X315520Y711720D03*
X325700Y711600D03*
X320320Y711720D03*
X305500Y721000D03*
X310500D03*
X304150Y674700D03*
X299350D03*
X334057Y755280D03*
X324057D03*
X314057D03*
X304057D03*
X294057D03*
X284057D03*
X279057D03*
X289057D03*
X299057D03*
X309057D03*
X319057D03*
X329057D03*
X339057D03*
X305500Y726000D03*
X310500D03*
X368500Y591900D03*
X381638Y755280D03*
X384809Y752321D03*
X387045Y747849D03*
X389281Y743376D03*
X391517Y738904D03*
X393753Y734432D03*
X395989Y729960D03*
X398225Y725488D03*
X344057Y755280D03*
X521634Y38901D03*
Y34101D03*
X516834Y38901D03*
Y34101D03*
X526434Y43701D03*
X521634D03*
X516834D03*
X520000Y63400D03*
X515200Y66440D03*
X520585Y68348D03*
X519900Y103150D03*
X533080Y108300D03*
X520000Y108700D03*
X536794Y77373D03*
X531664Y78463D03*
X515915Y80576D03*
X520310Y76700D03*
X508668Y79607D03*
X503550Y79500D03*
X511100Y75060D03*
X506100D03*
X511100Y70060D03*
X525200Y71440D03*
X516628Y71806D03*
X600700Y35700D03*
X595500Y35600D03*
X595700Y29800D03*
X600900Y29700D03*
X594000Y151500D03*
X600000D03*
X587300Y151400D03*
X576610Y388416D03*
Y393416D03*
X576512Y369625D03*
Y364825D03*
X581312Y369625D03*
Y364825D03*
X576610Y398416D03*
Y403416D03*
Y408416D03*
Y413416D03*
Y418416D03*
Y423416D03*
Y428416D03*
Y433416D03*
Y438416D03*
Y443416D03*
Y448416D03*
Y453416D03*
Y458416D03*
Y463416D03*
Y468416D03*
Y473416D03*
Y478416D03*
Y483416D03*
Y488416D03*
Y493416D03*
Y498416D03*
Y503416D03*
Y508416D03*
Y513416D03*
Y518416D03*
Y523416D03*
Y528416D03*
Y533416D03*
Y538416D03*
Y543416D03*
Y548416D03*
Y553416D03*
Y558416D03*
Y563416D03*
Y568416D03*
Y573416D03*
Y578416D03*
Y583416D03*
Y588416D03*
Y593416D03*
Y598416D03*
Y603416D03*
Y608416D03*
Y613416D03*
Y618416D03*
Y623416D03*
Y628416D03*
Y633416D03*
Y638416D03*
Y643416D03*
Y648416D03*
Y653416D03*
Y658416D03*
Y663416D03*
Y668416D03*
Y673416D03*
Y678416D03*
Y683416D03*
Y688416D03*
Y693416D03*
Y698416D03*
Y703416D03*
Y708416D03*
Y713416D03*
Y718416D03*
X577063Y723309D03*
X579299Y727781D03*
X581535Y732253D03*
X583771Y736725D03*
X586007Y741198D03*
X588243Y745670D03*
X590479Y750142D03*
X592715Y754614D03*
X616300Y151400D03*
X610900Y151500D03*
X605400Y151400D03*
X622310Y157470D03*
X621600Y151600D03*
X609200Y330400D03*
X658000Y431500D03*
Y409000D03*
Y414000D03*
Y426000D03*
Y420500D03*
X642700Y454400D03*
X642500Y449100D03*
X642600Y459500D03*
X610000Y467500D03*
X609000Y473500D03*
Y478500D03*
Y483500D03*
X645200Y521900D03*
X650400Y517600D03*
X656400Y517500D03*
X661500Y517600D03*
X621600Y486619D03*
X626958Y486419D03*
X642500Y464700D03*
X629500Y482500D03*
Y477000D03*
Y471500D03*
X635000Y482500D03*
Y476500D03*
Y471000D03*
X615500Y529800D03*
X616710Y534500D03*
X657000Y555000D03*
X662000D03*
X661887Y560010D03*
X656887D03*
X645300Y655200D03*
Y650400D03*
Y645600D03*
Y640800D03*
X655000Y705000D03*
Y700200D03*
Y695400D03*
Y690600D03*
X645300Y684000D03*
Y679200D03*
Y674400D03*
Y669600D03*
Y664800D03*
Y660000D03*
X655000Y685800D03*
X659722Y755280D03*
X649722D03*
X639722D03*
X634722D03*
X644722D03*
X654722D03*
X664722D03*
X730000Y196800D03*
X724700D03*
X681700Y155600D03*
X678100Y151500D03*
X697400Y155500D03*
X693400Y151700D03*
X689400Y155500D03*
X705300Y155100D03*
X685600Y151400D03*
X701100Y151600D03*
X726000Y322000D03*
X720613Y321539D03*
X693300Y297000D03*
X691200Y306300D03*
X706300Y319900D03*
X696000Y311100D03*
X699000Y290100D03*
X696200Y301700D03*
X713400Y316800D03*
X699300Y306900D03*
X708483Y311988D03*
X713283D03*
X723900Y326350D03*
X718940Y326270D03*
X732000Y341400D03*
X732600Y346900D03*
X722500Y341000D03*
X714900Y453600D03*
X715200Y459600D03*
X706700Y413900D03*
X710200Y417400D03*
Y422900D03*
Y427900D03*
X698700Y417600D03*
Y423100D03*
Y428100D03*
X676000Y431000D03*
X671000D03*
Y421000D03*
X676000D03*
X671000Y426000D03*
X676000D03*
X715200Y465000D03*
X689500Y518500D03*
Y524000D03*
X694738Y523940D03*
X694690Y519034D03*
X670400Y565500D03*
Y560700D03*
Y555900D03*
Y551100D03*
Y546300D03*
Y541500D03*
Y536700D03*
X687015Y658100D03*
Y653300D03*
Y648500D03*
Y643700D03*
Y682100D03*
X673950Y686104D03*
Y691104D03*
Y696104D03*
Y701104D03*
Y706104D03*
X687015Y677300D03*
Y672500D03*
Y667700D03*
Y662900D03*
X729722Y755280D03*
X719722D03*
X709722D03*
X699722D03*
X689722D03*
X679722D03*
X669722D03*
X674722D03*
X684722D03*
X694722D03*
X704722D03*
X714722D03*
X724722D03*
X734722D03*
X780100Y8500D03*
X775100D03*
X770100D03*
X765100D03*
X760100D03*
X755100D03*
X750100D03*
X745100D03*
X787895D03*
X797895D03*
X792895D03*
X787900Y196700D03*
X793200D03*
X798700D03*
X775600D03*
X780500Y190500D03*
X782500Y196800D03*
X770300Y196700D03*
X758947Y196761D03*
X735500Y196800D03*
X740900Y196750D03*
X752922Y196789D03*
X754000Y172700D03*
Y177500D03*
X738586Y340730D03*
X798359Y351659D03*
X795193Y355540D03*
X791786Y359001D03*
X735484Y429378D03*
Y434178D03*
Y462978D03*
Y458178D03*
Y453378D03*
Y448578D03*
Y443778D03*
Y438978D03*
X798000Y459300D03*
X740300Y427100D03*
Y431900D03*
X751100Y405400D03*
X755900D03*
X760700D03*
X765500D03*
X770300D03*
X775100D03*
X740300Y446300D03*
Y441500D03*
Y436700D03*
X790600Y458000D03*
X781000D03*
X785800D03*
X776200D03*
X789500Y405400D03*
X784700D03*
X779900D03*
X750000Y427100D03*
X754800D03*
X783800Y436000D03*
X779000D03*
X793400D03*
X788600D03*
X788400Y427100D03*
X783600D03*
X778800D03*
X774200Y436000D03*
X774000Y427100D03*
X769200D03*
X764400D03*
X759600D03*
X735484Y467778D03*
X799722Y755280D03*
X789722D03*
X779722D03*
X769722D03*
X759722D03*
X749722D03*
X739722D03*
X744722D03*
X754722D03*
X764722D03*
X774722D03*
X784722D03*
X794722D03*
X807895Y8500D03*
X817895D03*
X827895D03*
X837895D03*
X847895D03*
X857895D03*
X862895D03*
X852895D03*
X842895D03*
X832895D03*
X822895D03*
X812895D03*
X802895D03*
X810500Y196700D03*
X804600D03*
X842600Y339400D03*
X841100Y332300D03*
X826993Y358840D03*
X821502Y358356D03*
X827145Y363638D03*
X821653Y363488D03*
X826900Y332500D03*
X825300Y339900D03*
X825100Y347300D03*
X828100Y352900D03*
X809792Y379122D03*
X814592D03*
X809792Y374322D03*
X814592D03*
X842900Y347200D03*
X840800Y352800D03*
X828000Y459300D03*
X823200D03*
X832800D03*
X818400D03*
X807600D03*
X802800D03*
X812400D03*
X864727Y398458D03*
X804300Y436500D03*
X813900D03*
X809100D03*
X818700D03*
X823500D03*
X830100Y501500D03*
X839700D03*
X834900D03*
X827000Y516000D03*
X832000D03*
Y521000D03*
X827000D03*
X843900Y464000D03*
X848700Y465200D03*
Y470600D03*
X849722Y755280D03*
X839722D03*
X829722D03*
X819722D03*
X809722D03*
X804722D03*
X814722D03*
X824722D03*
X834722D03*
X844722D03*
X854722D03*
X867895Y8500D03*
X877895D03*
X887895D03*
X897895D03*
X907895D03*
X916697Y19698D03*
Y29698D03*
Y39698D03*
Y49698D03*
Y59698D03*
Y69698D03*
Y64698D03*
Y54698D03*
Y44698D03*
Y34698D03*
Y24698D03*
Y14698D03*
X912895Y8500D03*
X902895D03*
X892895D03*
X882895D03*
X872895D03*
X916697Y79698D03*
Y89698D03*
Y99698D03*
Y109698D03*
Y119698D03*
Y129698D03*
Y134698D03*
Y124698D03*
Y114698D03*
Y104698D03*
Y94698D03*
Y84698D03*
Y74698D03*
Y139698D03*
Y149698D03*
Y159698D03*
Y169698D03*
Y179698D03*
Y189698D03*
Y199698D03*
Y194698D03*
Y184698D03*
Y174698D03*
Y164698D03*
Y154698D03*
Y144698D03*
Y209698D03*
Y219698D03*
Y229698D03*
Y239698D03*
Y249698D03*
Y259698D03*
Y264698D03*
Y254698D03*
Y244698D03*
Y234698D03*
Y224698D03*
Y214698D03*
Y204698D03*
Y269698D03*
Y279698D03*
Y289698D03*
Y299698D03*
Y309698D03*
Y319698D03*
Y329698D03*
Y324698D03*
Y314698D03*
Y304698D03*
Y294698D03*
Y284698D03*
Y274698D03*
Y339698D03*
Y349698D03*
Y359698D03*
Y369698D03*
Y379698D03*
Y389698D03*
Y394698D03*
Y384698D03*
Y374698D03*
Y364698D03*
Y354698D03*
Y344698D03*
Y334698D03*
X881147Y394517D03*
X916697Y399698D03*
Y409698D03*
Y419698D03*
Y429698D03*
Y439698D03*
Y449698D03*
Y459698D03*
Y454698D03*
Y444698D03*
Y434698D03*
Y424698D03*
Y414698D03*
Y404698D03*
X874727Y398458D03*
X869727D03*
X880887Y399474D03*
X916697Y469698D03*
Y479698D03*
Y489698D03*
Y499698D03*
Y509698D03*
Y519698D03*
Y524698D03*
Y514698D03*
Y504698D03*
Y494698D03*
Y484698D03*
Y474698D03*
Y464698D03*
Y529698D03*
Y539698D03*
Y549698D03*
Y559698D03*
Y569698D03*
Y579698D03*
Y589698D03*
Y584698D03*
Y574698D03*
Y564698D03*
Y554698D03*
Y544698D03*
Y534698D03*
Y599698D03*
Y609698D03*
Y619698D03*
Y629698D03*
Y639698D03*
Y649698D03*
Y659698D03*
Y654698D03*
Y644698D03*
Y634698D03*
Y624698D03*
Y614698D03*
Y604698D03*
Y594698D03*
Y669698D03*
Y679698D03*
Y689698D03*
Y699698D03*
Y709698D03*
Y719698D03*
Y714698D03*
Y704698D03*
Y694698D03*
Y684698D03*
Y674698D03*
Y664698D03*
X914700Y726100D03*
X912436Y730603D03*
X910200Y735300D03*
X907564Y739747D03*
X905500Y744400D03*
X903192Y748791D03*
X900800Y753700D03*
X894722Y755280D03*
G54D103*
G01X619980Y197550D02*
X601189Y216340D01*
Y316438D01*
X595298Y322329D01*
Y368800D01*
X596077Y369579D01*
G01X644100Y203350D02*
X636799D01*
X630999Y197550D01*
X619980D01*
X421653Y126378D03*
X435827D03*
X450000D03*
X464173D03*
X428740Y121654D03*
X442913D03*
X457086D03*
X471260D03*
X421653Y130709D03*
X428740Y125985D03*
X435827Y130709D03*
X442913Y125985D03*
X450000Y130709D03*
X457086Y125985D03*
X464173Y130709D03*
X471260Y125985D03*
X428740Y131496D03*
X442913D03*
X457086D03*
X471260D03*
X421653Y183071D03*
X435827D03*
X450000D03*
X464173D03*
X421653Y136221D03*
X435827D03*
X450000D03*
X464173D03*
X421653Y140551D03*
X428740Y135827D03*
X435827Y140551D03*
X442913Y135827D03*
X450000Y140551D03*
X457086Y135827D03*
X464173Y140551D03*
X471260Y135827D03*
X421653Y144882D03*
X428740Y140158D03*
X435827Y144882D03*
X442913Y140158D03*
X450000Y144882D03*
X457086Y140158D03*
X464173Y144882D03*
X471260Y140158D03*
X421653Y150394D03*
X428740Y145670D03*
X435827Y150394D03*
X442913Y145670D03*
X450000Y150394D03*
X457086Y145670D03*
X464173Y150394D03*
X471260Y145670D03*
X421653Y154725D03*
X428740Y150000D03*
X435827Y154725D03*
X442913Y150000D03*
X450000Y154725D03*
X457086Y150000D03*
X464173Y154725D03*
X471260Y150000D03*
X421653Y159055D03*
X428740Y154331D03*
X435827Y159055D03*
X442913Y154331D03*
X450000Y159055D03*
X457086Y154331D03*
X464173Y159055D03*
X471260Y154331D03*
X421653Y164567D03*
X428740Y159843D03*
X435827Y164567D03*
X442913Y159843D03*
X450000Y164567D03*
X457086Y159843D03*
X464173Y164567D03*
X471260Y159843D03*
X421653Y168898D03*
X428740Y164173D03*
X435827Y168898D03*
X442913Y164173D03*
X450000Y168898D03*
X457086Y164173D03*
X464173Y168898D03*
X471260Y164173D03*
X421653Y173229D03*
X428740Y168504D03*
X435827Y173229D03*
X442913Y168504D03*
X450000Y173229D03*
X457086Y168504D03*
X464173Y173229D03*
X471260Y168504D03*
X421653Y178740D03*
X428740Y174016D03*
X435827Y178740D03*
X442913Y174016D03*
X450000Y178740D03*
X457086Y174016D03*
X464173Y178740D03*
X471260Y174016D03*
X506693Y126378D03*
X520866D03*
X535039D03*
X513779Y121654D03*
X527953D03*
X506693Y130709D03*
X513779Y125985D03*
X520866Y130709D03*
X527953Y125985D03*
X535039Y130709D03*
X513779Y131496D03*
X527953D03*
X506693Y183071D03*
X520866D03*
X535039D03*
X506693Y136221D03*
X520866D03*
X535039D03*
X506693Y140551D03*
X513779Y135827D03*
X520866Y140551D03*
X527953Y135827D03*
X535039Y140551D03*
X506693Y144882D03*
X513779Y140158D03*
X520866Y144882D03*
X527953Y140158D03*
X535039Y144882D03*
X506693Y150394D03*
X513779Y145670D03*
X520866Y150394D03*
X527953Y145670D03*
X535039Y150394D03*
X506693Y154725D03*
X513779Y150000D03*
X520866Y154725D03*
X527953Y150000D03*
X535039Y154725D03*
X506693Y159055D03*
X513779Y154331D03*
X520866Y159055D03*
X527953Y154331D03*
X535039Y159055D03*
X506693Y164567D03*
X513779Y159843D03*
X520866Y164567D03*
X527953Y159843D03*
X535039Y164567D03*
X506693Y168898D03*
X513779Y164173D03*
X520866Y168898D03*
X527953Y164173D03*
X535039Y168898D03*
X506693Y173229D03*
X513779Y168504D03*
X520866Y173229D03*
X527953Y168504D03*
X535039Y173229D03*
X506693Y178740D03*
X513779Y174016D03*
X520866Y178740D03*
X527953Y174016D03*
X535039Y178740D03*
X549212Y126378D03*
X542126Y121654D03*
X556299D03*
X542126Y125985D03*
X549212Y130709D03*
X556299Y125985D03*
X542126Y131496D03*
X556299D03*
X549212Y183071D03*
Y136221D03*
X542126Y135827D03*
X549212Y140551D03*
X556299Y135827D03*
X542126Y140158D03*
X549212Y144882D03*
X556299Y140158D03*
X542126Y145670D03*
X549212Y150394D03*
X556299Y145670D03*
X542126Y150000D03*
X549212Y154725D03*
X556299Y150000D03*
X542126Y154331D03*
X549212Y159055D03*
X556299Y154331D03*
X542126Y159843D03*
X549212Y164567D03*
X556299Y159843D03*
X542126Y164173D03*
X549212Y168898D03*
X556299Y164173D03*
X542126Y168504D03*
X549212Y173229D03*
X556299Y168504D03*
X542126Y174016D03*
X549212Y178740D03*
X556299Y174016D03*
G54D122*
X614750Y555400D03*
X718650Y576300D03*
G54D113*
X599998Y386961D03*
X589873Y379461D03*
X593748Y386961D03*
X585998D03*
X603873Y379461D03*
X607748Y386961D03*
X767684Y524500D03*
X786584Y525000D03*
X771559Y532000D03*
X763809D03*
X790459Y532500D03*
X782709D03*
G54D20*
X50960Y58330D03*
Y47330D03*
X71090Y63300D03*
Y52300D03*
X632460Y164580D03*
Y153580D03*
X659200Y538200D03*
Y549200D03*
X758435Y410973D03*
Y421973D03*
X767135Y410973D03*
Y421973D03*
X775835Y410973D03*
Y421973D03*
X790300Y452400D03*
Y441400D03*
X749700Y411000D03*
Y422000D03*
X781400Y452400D03*
Y441400D03*
X864928Y382092D03*
Y393092D03*
X873623Y382038D03*
Y393038D03*
G54D104*
X535048Y54803D03*
Y48397D03*
G54D131*
X710389Y567956D03*
X708420D03*
X706452D03*
X704483D03*
X702515D03*
X700546D03*
X698577D03*
X696609D03*
X694640D03*
X692672D03*
X690703D03*
Y587242D03*
X692672D03*
X694640D03*
X696609D03*
X698577D03*
X700546D03*
X702515D03*
X704483D03*
X706452D03*
X708420D03*
X710389D03*
G54D11*
X80708Y44292D03*
X61024Y34449D03*
X33464D03*
X56102Y24606D03*
X38386D03*
X108268Y44292D03*
X103346Y34449D03*
X85630D03*
X590300Y574400D03*
X600300D03*
X610300D03*
G54D140*
X818018Y260200D03*
X820218D03*
X818018Y262400D03*
X820218D03*
X818018Y255800D03*
X820218D03*
X818018Y253600D03*
X820218D03*
X818018Y266800D03*
X820218D03*
X818018Y269000D03*
X820218D03*
X818018Y273400D03*
X820218D03*
X818018Y275600D03*
X820218D03*
X818018Y280000D03*
X820218D03*
X818018Y282200D03*
X820218D03*
X818018Y286600D03*
X820218D03*
X818018Y288800D03*
X820218D03*
X818018Y293200D03*
X820218D03*
X818018Y295400D03*
X820218D03*
X818018Y299800D03*
X820218D03*
X818018Y302000D03*
X820218D03*
G54D150*
G01X203650Y633100D02*
X204685Y632065D01*
Y625403D01*
X207238Y622850D01*
Y616738D01*
X205000Y614500D01*
G01X203650Y633100D02*
X206990D01*
X207060Y633170D01*
G01X198819Y603937D02*
Y607319D01*
X205000Y613500D01*
Y614500D01*
G01X211600Y614400D02*
X209699Y612499D01*
X207567D01*
X200269Y605201D01*
Y602237D01*
X198819Y600787D01*
G01X207060Y629670D02*
X208268D01*
X208578Y629360D01*
X210520D01*
G01X194094Y602362D02*
X195669Y603937D01*
G01X194093Y596063D02*
Y596062D01*
X192519Y594488D01*
G01X188400Y647450D02*
X192430D01*
X194490Y645390D01*
G01X211600Y614400D02*
Y616681D01*
X210200Y618081D01*
Y623319D01*
X210650Y623769D01*
Y629230D01*
X210520Y629360D01*
G01X796875Y304331D02*
Y300369D01*
X798425Y298819D01*
G54D30*
X64884Y643900D03*
X148700Y691600D03*
X204286Y698355D03*
X146649Y740015D03*
X275600Y715100D03*
X298400Y524750D03*
X302919Y553653D03*
X294300Y543000D03*
X305670Y612350D03*
X285460Y644250D03*
X294804Y688120D03*
X380800Y543200D03*
X362586Y639880D03*
X353830Y702620D03*
X446135Y34357D03*
X630322Y368128D03*
X613710Y521543D03*
X620300Y467000D03*
X625460Y554943D03*
X642900Y557500D03*
X744630Y452700D03*
X818034Y389702D03*
X809500Y477200D03*
G54D12*
X38780Y48060D03*
X76100Y690300D03*
X89034Y55935D03*
X110220Y481998D03*
X142100Y519900D03*
X105920Y489718D03*
X110220Y489678D03*
X108600Y570550D03*
X123900Y648000D03*
X127900D03*
X140700Y650100D03*
X111200Y709900D03*
X80600Y685500D03*
X203500Y516900D03*
X199500Y517000D03*
X184167Y502984D03*
X183277Y485678D03*
X178920D03*
X151900Y633900D03*
X147800D03*
X168900Y633600D03*
X149400Y622800D03*
X193285Y621100D03*
X189185D03*
X185085D03*
X181085D03*
X177000Y620000D03*
X172900D03*
X164800Y633600D03*
X197555Y633257D03*
X200850Y643000D03*
X145300Y622800D03*
X208516Y653501D03*
X196648Y653621D03*
X161000Y644300D03*
X144800Y650100D03*
X164349Y695415D03*
X151749Y695715D03*
X166400Y704800D03*
X154300Y703515D03*
X216900Y512266D03*
X212600Y517000D03*
X225600Y515380D03*
X269600Y528100D03*
X252272Y613181D03*
X225900Y623700D03*
X229900Y625000D03*
X221900Y623700D03*
X238000Y622800D03*
X234000D03*
X223400Y638000D03*
X244156Y613787D03*
X242900Y675700D03*
X258431Y704490D03*
X249842Y707310D03*
X339851Y179517D03*
X340942Y528526D03*
X314181Y586050D03*
X297175Y535054D03*
X305100Y658100D03*
X289800Y660500D03*
X328000Y669900D03*
X291700Y730200D03*
X287620Y730220D03*
X370682Y192874D03*
X350000Y521000D03*
X354440Y485830D03*
X356680Y585664D03*
X374292Y583400D03*
X350000Y529000D03*
X385600Y532500D03*
X345900Y578100D03*
X392133Y594490D03*
X468200Y62600D03*
X463200Y55700D03*
X444754Y42401D03*
X472500Y62500D03*
X639067Y358591D03*
X613223Y372527D03*
X637147Y396797D03*
X646469Y417486D03*
X632628Y554627D03*
X727150Y187850D03*
X722150D03*
X725678Y176992D03*
X711150Y177600D03*
X716650Y187850D03*
X705650D03*
X711150D03*
X714090Y324840D03*
X706000Y324800D03*
X727200Y356100D03*
X722500Y346300D03*
X713500Y356200D03*
X718000Y346300D03*
X689000Y499800D03*
X713575Y552777D03*
X728000Y580250D03*
X703800Y601500D03*
X784161Y123415D03*
X784400Y99300D03*
X741300Y188800D03*
X758100Y188400D03*
X754000Y188800D03*
X738365Y356035D03*
X790400Y416400D03*
X795922Y522908D03*
X777200Y496800D03*
X759200Y500800D03*
X753099Y523066D03*
X748899Y522966D03*
X818688Y403255D03*
X857000Y403400D03*
X805249Y519877D03*
X885568Y318641D03*
G54D141*
X892449Y237028D03*
Y230972D03*
X888551Y237028D03*
Y230972D03*
G54D114*
X629921Y57874D03*
X708661D03*
G54D132*
X679800Y634661D03*
Y599739D03*
G54D105*
X529093Y39585D03*
Y34585D03*
Y29585D03*
Y24585D03*
G54D123*
X627160Y538043D03*
G54D21*
G01X-13131Y-65072D02*
Y-145072D01*
G01D02*
X1244069D01*
G01X-29131Y-65072D02*
Y-33072D01*
G01X-13131Y-65072D02*
X1244069D01*
G01X-13131Y-100572D02*
X1244069D01*
G01X-17131Y-49072D02*
G02I-12000J0D01*
G01X-22281D02*
G02I-6850J0D01*
G01X-13131D02*
X-45131D01*
G01X34070Y54070D02*
X29890D01*
G01X38780Y51510D02*
Y55070D01*
X38590Y55260D01*
G01X76506Y44292D02*
X80708D01*
G01X29262Y34449D02*
X33464D01*
G01D02*
X37666D01*
G01X56822D02*
X61024D01*
G01D02*
X65226D01*
G01X75405Y517527D02*
Y521695D01*
G01X69778Y517527D02*
Y521695D01*
G01X44256Y543876D02*
X52408D01*
G01X52603Y549526D02*
X52577Y549500D01*
X44050D01*
G01X52485Y555153D02*
X44237D01*
G01X44156Y532622D02*
X53524D01*
G01X52613Y538242D02*
X52606Y538249D01*
X44256D01*
G01X64796Y647850D02*
Y650896D01*
X64884Y650984D01*
G01X43850Y660700D02*
X40309D01*
G01X71800Y691700D02*
Y698850D01*
X71850Y698900D01*
G01X46100Y671534D02*
Y666550D01*
X47150Y665500D01*
G01X76100Y697100D02*
Y693750D01*
G01X93640Y60860D02*
X98770D01*
G01X84616Y60675D02*
Y64464D01*
X84610Y64470D01*
G01X89034Y59385D02*
Y62564D01*
X89070Y62600D01*
G01X108268Y40090D02*
Y44292D01*
G01D02*
Y48494D01*
G01Y44292D02*
X112470D01*
G01X80708Y40090D02*
Y44292D01*
G01D02*
Y48494D01*
G01X135012Y514552D02*
Y510200D01*
G01X101100Y511850D02*
X105350D01*
G01X119400Y511500D02*
Y513550D01*
X117700Y515250D01*
G01X110220Y481948D02*
X114070D01*
G01X132100Y493000D02*
X129399Y490299D01*
X126185D01*
G01X142000Y512050D02*
Y508590D01*
X141980D01*
G01X93531Y492891D02*
X97637D01*
G01X105920Y481948D02*
Y477098D01*
G01X118900Y522000D02*
X117700Y520800D01*
Y518750D01*
G01D02*
X121550D01*
X123848Y521048D01*
X125788D01*
G01X92000Y517450D02*
Y521409D01*
X92286Y521695D01*
G01X81032Y517527D02*
Y521695D01*
G01X86659Y517527D02*
Y521695D01*
G01X101113Y522827D02*
X99045D01*
X97913Y521695D01*
G01X108600Y574000D02*
Y577029D01*
X108371Y577258D01*
G01X126950Y530300D02*
X123300D01*
G01X85500Y632750D02*
Y628500D01*
G01X136100Y651450D02*
Y656300D01*
G01X123370Y606700D02*
Y604112D01*
X122947Y603689D01*
Y601923D01*
G01X119953Y609818D02*
X119600Y609465D01*
Y606700D01*
G01X122650Y636400D02*
X120950Y638100D01*
X118500D01*
G01X140700Y653550D02*
Y657700D01*
G01X127900Y651450D02*
Y653200D01*
X130800Y656100D01*
G01X132100Y651450D02*
Y654800D01*
X130800Y656100D01*
G01X115619Y706995D02*
X112795D01*
X111300Y705500D01*
G01X107100Y679600D02*
Y682801D01*
X98901Y691000D01*
X82650D01*
X80600Y688950D01*
G01X132651Y740015D02*
X138509D01*
X138653Y739871D01*
G01X143099Y740015D02*
X142955Y739871D01*
X138653D01*
G01X182994Y459767D02*
X186602D01*
G01X183068Y463748D02*
X186735D01*
G01X200850Y502800D02*
Y503943D01*
X203307Y506400D01*
G01X203500Y516850D02*
Y513500D01*
G01X199500Y516950D02*
X203400D01*
X203500Y516850D01*
G01X178920Y478048D02*
X176148D01*
X175100Y477000D01*
G01X208650Y499300D02*
Y501850D01*
X207500Y503000D01*
G01X179568Y463748D02*
X172320D01*
X172370Y463798D01*
G01X208650Y495300D02*
X208500Y495150D01*
Y491700D01*
X208370Y491570D01*
G01X184167Y502934D02*
Y500867D01*
X183100Y499800D01*
G01X146112Y509412D02*
Y513048D01*
G01D02*
X150112D01*
G01X178869Y516943D02*
Y513593D01*
G01X182874Y516941D02*
Y513591D01*
G01X166600Y516950D02*
Y513600D01*
G01X170700Y516950D02*
Y513600D01*
G01X182994Y469867D02*
X185133D01*
X187000Y468000D01*
G01X183320Y478048D02*
X186252D01*
X186600Y477700D01*
G01X172370Y463798D02*
X170770D01*
X169269Y465299D01*
X164039D01*
G01X207900Y641450D02*
Y645600D01*
G01X204357Y656936D02*
Y659343D01*
X202800Y660900D01*
G01X200532Y657153D02*
Y658632D01*
X202800Y660900D01*
G01X191746Y657092D02*
Y657900D01*
X189746Y659900D01*
X189000D01*
G01X188400Y643950D02*
X185000D01*
X184967Y643983D01*
G01X144800Y653550D02*
Y657900D01*
G01X203650Y636600D02*
X202110D01*
X200560Y635100D01*
G01D02*
X199003Y636707D01*
X197555D01*
G01X165000Y644250D02*
Y640400D01*
X164800Y640200D01*
G01Y637050D02*
Y640200D01*
G01X193500Y663000D02*
X194700Y664200D01*
X206877D01*
X208900Y662177D01*
Y660022D01*
X208516Y659638D01*
Y656951D01*
G01X196900Y661350D02*
Y660700D01*
X196648Y660448D01*
Y657071D01*
G01X200850Y646450D02*
Y646800D01*
X203398Y649348D01*
Y649598D01*
X203400Y649600D01*
G01X197087Y679921D02*
X191767D01*
X191766Y679920D01*
G01X154300Y703465D02*
X151130D01*
Y703440D01*
G01X151749Y695665D02*
X148349D01*
X148249Y695765D01*
G01X200736Y698355D02*
X196855D01*
G01X158599Y711215D02*
X162100D01*
G01X159519Y694455D02*
X158309Y695665D01*
X155849D01*
G01X272000Y461800D02*
Y458750D01*
X271450Y458200D01*
G01X268350Y461950D02*
Y465400D01*
G01X242700Y518670D02*
X244000D01*
X246000Y516670D01*
G01X271850Y465400D02*
X274700D01*
X275500Y466200D01*
G01X271850Y490300D02*
X275700D01*
G01X245743Y532802D02*
Y528143D01*
X244900Y527300D01*
G01X271450Y470300D02*
X275400D01*
G01X268350Y465400D02*
X268250Y465300D01*
X259079D01*
G01X257000Y548400D02*
X258324Y549724D01*
Y552061D01*
G01X264150Y552100D02*
Y553680D01*
X263219Y554611D01*
Y554694D01*
X263216Y554697D01*
G01X251516Y567108D02*
Y563079D01*
X251527Y563068D01*
G01X251446Y556761D02*
Y553754D01*
G01X254500Y579500D02*
X253220Y578220D01*
X250980D01*
X250900Y578300D01*
G01X251150Y573500D02*
X250740Y573910D01*
Y578140D01*
X250900Y578300D01*
G01X273500Y567400D02*
Y568850D01*
X270250Y572100D01*
G01X251150Y585700D02*
X253500D01*
X254300Y586500D01*
G01X257300Y537500D02*
Y537800D01*
X259000Y539500D01*
X260750D01*
G01X254530Y564300D02*
X253298Y563068D01*
X251527D01*
G01X213800Y631200D02*
X212140Y632860D01*
X210520D01*
G01X234000Y626250D02*
X238000D01*
G01X252250Y656375D02*
X247725D01*
G01X221900Y627150D02*
Y630800D01*
G01X270521Y618515D02*
Y622749D01*
X270400Y622870D01*
G01X259750Y648625D02*
X263785D01*
X264040Y648370D01*
G01X211706Y641442D02*
Y645349D01*
G01X215406Y641442D02*
X211706D01*
G01X263257Y626253D02*
X266847D01*
G01X231300Y645550D02*
Y648700D01*
X230900Y649100D01*
G01X227500Y645550D02*
X231300D01*
G01X272350Y639000D02*
Y637450D01*
X274800Y635000D01*
G01X248215Y613137D02*
Y610135D01*
X248450Y609900D01*
G01X234000Y626250D02*
Y629576D01*
G01X222950Y647900D02*
Y641900D01*
X223400Y641450D01*
G01X255570Y616631D02*
X252272D01*
G01X278443Y648857D02*
Y647293D01*
X274150Y643000D01*
X270050D01*
G01X236350Y637600D02*
X236000Y637950D01*
Y647400D01*
G01X243400Y639450D02*
X241300D01*
X239450Y637600D01*
X236350D01*
G01X225900Y630700D02*
Y627150D01*
G01Y630700D02*
X226622D01*
X228872Y628450D01*
X229900D01*
G01X228066Y658967D02*
X231367D01*
X231500Y659100D01*
G01X234750Y633200D02*
X235500Y633950D01*
Y636750D01*
X236350Y637600D01*
G01X263146Y630071D02*
X266571D01*
G01X252250Y670375D02*
X247825D01*
G01X230315Y679921D02*
X235100D01*
G01X221575Y688956D02*
Y695400D01*
G01X262645Y707951D02*
Y711222D01*
X262634Y711233D01*
G01X261769Y662209D02*
X264635D01*
X265000Y662574D01*
G01X263000Y675750D02*
X265999D01*
X266400Y675349D01*
G01X272503Y704787D02*
X268013D01*
X267880Y704920D01*
G01X266800Y671050D02*
Y674949D01*
X266400Y675349D01*
G01X265000Y662574D02*
Y663750D01*
X262650Y666100D01*
G01X272050Y711810D02*
Y715100D01*
G01X251900Y676250D02*
X252550Y675600D01*
X254900D01*
X255050Y675750D01*
G01D02*
X258500D01*
G01X258431Y707940D02*
Y711335D01*
X258423Y711343D01*
G01X270900Y670550D02*
Y667200D01*
G01X231500Y659100D02*
X235450D01*
G01X268520Y719420D02*
X271470D01*
X271970Y718920D01*
G01X263000Y679250D02*
X266050D01*
X266200Y679400D01*
G01X258431Y704440D02*
X262634D01*
X262645Y704451D01*
G01X345175Y117460D02*
X340385D01*
X340297Y117548D01*
G01X345175Y113960D02*
X339232D01*
G01X328972Y210884D02*
Y185792D01*
X331797Y182967D01*
X339851D01*
G01X297146Y202165D02*
X305703D01*
G01X314666Y255709D02*
X319921D01*
X321197Y254433D01*
G01X314666Y252559D02*
X319323D01*
X321197Y254433D01*
G01X314666Y265158D02*
X319953D01*
X321281Y266486D01*
G01X297146Y230512D02*
X302144D01*
X305182Y227474D01*
X305382D01*
G01X306407Y206057D02*
X308815Y208465D01*
X314666D01*
G01X297146Y205315D02*
X305665D01*
X306407Y206057D01*
G01X297146Y258858D02*
X302041D01*
X304231Y261048D01*
G01X297146Y262008D02*
X303271D01*
X304231Y261048D01*
G01X305703Y202165D02*
X306765D01*
X309915Y205315D01*
X314666D01*
G01X297146Y208465D02*
X304313D01*
X305862Y210014D01*
G01X335000Y226992D02*
X335512Y227504D01*
X339685D01*
X340197Y226992D01*
G01X297146Y284055D02*
X302130D01*
X304267Y286192D01*
G01X297146Y287205D02*
X303254D01*
X304267Y286192D01*
G01X297146Y309252D02*
X302127D01*
X304267Y311392D01*
G01X297146Y312402D02*
X303257D01*
X304267Y311392D01*
G01X297146Y321850D02*
X303225D01*
X304267Y322892D01*
G01X297146Y296654D02*
X303229D01*
X304267Y297692D01*
G01X314666Y331299D02*
X319617D01*
X321432Y329484D01*
G01X314666Y318701D02*
X319616D01*
X321432Y316885D01*
G01X314666Y306102D02*
X320154D01*
X321882Y304374D01*
G01X314666Y293504D02*
X320252D01*
X321882Y291874D01*
G01X314666Y280906D02*
X319616D01*
X321432Y279090D01*
G01X314666Y268308D02*
X319459D01*
X321281Y266486D01*
G01X314666Y277756D02*
X320098D01*
X321432Y279090D01*
G01X314666Y290354D02*
X320362D01*
X321882Y291874D01*
G01X314666Y302953D02*
X320461D01*
X321882Y304374D01*
G01X314666Y315551D02*
X320098D01*
X321432Y316885D01*
G01X314666Y328150D02*
X319598D01*
X321432Y329484D01*
G01X297146Y299803D02*
X302156D01*
X304267Y297692D01*
G01X297146Y325000D02*
X302159D01*
X304267Y322892D01*
G01X297146Y274606D02*
X302173D01*
X304231Y272548D01*
G01X297146Y359646D02*
X302121D01*
X304267Y361792D01*
G01X297146Y362795D02*
X303264D01*
X304267Y361792D01*
G01X297146Y334449D02*
X302124D01*
X304267Y336592D01*
G01X297146Y337599D02*
X303260D01*
X304267Y336592D01*
G01X297146Y372244D02*
X303219D01*
X304267Y373292D01*
G01X297146Y347047D02*
X303222D01*
X304267Y348092D01*
G01X314666Y369095D02*
X319616D01*
X321432Y367279D01*
G01X314666Y356496D02*
X319617D01*
X321432Y354681D01*
G01X314666Y343898D02*
X319616D01*
X321432Y342082D01*
G01X314666Y340748D02*
X320098D01*
X321432Y342082D01*
G01X314666Y353347D02*
X319598D01*
X321432Y354681D01*
G01X314666Y365945D02*
X320098D01*
X321432Y367279D01*
G01X297146Y350197D02*
X302162D01*
X304267Y348092D01*
G01X297146Y375394D02*
X302165D01*
X304267Y373292D01*
G01X294850Y524750D02*
Y522613D01*
X293793Y521556D01*
G01X328636Y522525D02*
X329035Y522126D01*
Y519325D01*
G01X325136Y519316D02*
Y522525D01*
G01X333922Y527323D02*
X332908Y526309D01*
X330571D01*
G01X341928Y517086D02*
X340961Y516119D01*
Y511600D01*
G01X298350Y524750D02*
Y521473D01*
X298335Y521458D01*
G01X299900Y585750D02*
X301850D01*
X303100Y587000D01*
G01X296500Y585750D02*
X293200D01*
X292850Y586100D01*
G01X287600Y587000D02*
X291950D01*
X292850Y586100D01*
G01X314181Y586000D02*
X314207D01*
X316680Y583527D01*
G01X325447Y536109D02*
X328659D01*
G01X290750Y543000D02*
X286498D01*
X286000Y542502D01*
X285982D01*
G01X322277Y552193D02*
X324179Y554095D01*
X328509D01*
X330860Y551744D01*
G01X293271Y557248D02*
X296866Y553653D01*
X299369D01*
G01X325774Y547428D02*
X324509Y548693D01*
X322277D01*
G01X329766Y543816D02*
Y544454D01*
X327804Y546416D01*
X327712D01*
X326700Y547428D01*
X325774D01*
G01X334250Y592000D02*
Y590446D01*
X331700Y587896D01*
G01X296835Y591015D02*
X297185D01*
X297300Y590900D01*
X299450D01*
X300200Y590150D01*
G01X287600Y592000D02*
X292100D01*
X293200Y590900D01*
X296300D01*
X296415Y591015D01*
X296835D01*
G01X280646Y557150D02*
X280316Y557480D01*
X276817D01*
G01X303500Y582200D02*
X303450Y582250D01*
X299900D01*
G01D02*
X296500D01*
G01X330230Y531380D02*
X333572D01*
X333847Y531105D01*
G01X335915Y539609D02*
X337931D01*
X341740Y535800D01*
G01X286195Y530579D02*
X288977D01*
X293150Y534752D01*
Y535250D01*
G01X303520Y550085D02*
X302869Y550736D01*
Y553653D01*
G01D02*
X307820D01*
X309116Y554949D01*
G01X341740Y535800D02*
X340942Y535002D01*
Y531976D01*
G01X317600Y606850D02*
Y603300D01*
G01X305498Y620477D02*
X305470Y620505D01*
Y623734D01*
G01X278523Y637655D02*
X278546Y637632D01*
Y633450D01*
G01X281910Y644250D02*
Y640910D01*
X281900Y640900D01*
G01X286700Y622190D02*
X289050D01*
X291050Y620190D01*
Y617000D01*
G01X284495Y613130D02*
X283384Y612019D01*
X279745D01*
G01X278443Y648857D02*
X281003D01*
X281910Y647950D01*
G01X294832Y691947D02*
X294804Y691975D01*
Y695204D01*
G01X311636Y666104D02*
Y670318D01*
X311600Y670354D01*
G01X295018Y661582D02*
Y663299D01*
X296800Y665081D01*
G01X299900Y660900D02*
Y661981D01*
X296800Y665081D01*
G01X319600Y670450D02*
X319536Y670386D01*
Y666104D01*
G01X281000Y678000D02*
X282600Y679600D01*
Y682150D01*
G01X328000Y673350D02*
X326600D01*
X321800Y678150D01*
Y678500D01*
G01X305100Y661550D02*
Y664400D01*
X304400Y665100D01*
G01X340500Y711750D02*
X340570Y711749D01*
X345419Y706900D01*
X350700D01*
X353780Y703820D01*
Y702620D01*
G01X289800Y663950D02*
Y666800D01*
X288700Y667900D01*
G01X335750Y664700D02*
Y665491D01*
X336500Y666241D01*
Y670050D01*
G01X306470Y743570D02*
Y742200D01*
X306370D01*
Y738774D01*
G01X298570Y743670D02*
Y741900D01*
X298470D01*
Y738774D01*
G01X278523Y736405D02*
Y739990D01*
X278553Y740020D01*
G01X291700Y737000D02*
Y733650D01*
G01X287620Y733670D02*
Y737300D01*
G01X375018Y49223D02*
X381008D01*
X381173Y49058D01*
G01X381156Y54116D02*
X380863Y53823D01*
X375018D01*
G01X362000Y124000D02*
X358480Y127520D01*
Y153357D01*
X360924Y155801D01*
X367762D01*
G01X360500Y116700D02*
X348677D01*
X347917Y117460D01*
X345175D01*
G01X375000Y116000D02*
Y111000D01*
G01Y121000D02*
Y116000D01*
G01Y111000D02*
Y107300D01*
G01X351500Y112960D02*
X347434D01*
X346434Y113960D01*
X345175D01*
G01X415211Y71263D02*
X411341D01*
X380928Y101676D01*
Y164029D01*
X382878Y165979D01*
Y329515D01*
X383170Y329807D01*
G01X346457Y81065D02*
Y84567D01*
G01D02*
Y88069D01*
G01X342955Y84567D02*
X346457D01*
G01D02*
X349959D01*
G01X349004Y183080D02*
Y185302D01*
X348082Y186224D01*
G01X359882Y203458D02*
Y202771D01*
X362484Y200169D01*
G01X367022Y240684D02*
X365732D01*
X362722Y237674D01*
G01X366922Y245284D02*
X364792D01*
X362662Y243154D01*
X361792D01*
G01X360100Y453500D02*
X355800Y457800D01*
Y463900D01*
X345950Y473750D01*
Y498850D01*
X344500Y500300D01*
G01X359088Y521681D02*
X353581D01*
X353300Y521400D01*
G01D02*
X352850Y520950D01*
X350000D01*
G01X354440Y489280D02*
X355280D01*
X357450Y491450D01*
G01X344400Y505400D02*
X345380D01*
X347811Y507831D01*
G01X385600Y529107D02*
Y532450D01*
G01X356680Y585614D02*
Y583992D01*
X355012Y582324D01*
G01X389750Y568500D02*
X393911D01*
X393912Y568499D01*
G01X391549Y560150D02*
X385296D01*
X384950Y560496D01*
G01X361279Y581647D02*
X360820Y582106D01*
Y586786D01*
G01X345900Y581550D02*
X348339D01*
X348529Y581360D01*
X349000D01*
G01D02*
X351600Y583960D01*
Y585234D01*
X352480Y586114D01*
G01X379050Y539931D02*
X380850Y541731D01*
Y543100D01*
X380750Y543200D01*
G01X379088Y536681D02*
Y539893D01*
X379050Y539931D01*
G01X345287Y537509D02*
X343449D01*
X341740Y535800D01*
G01X355000Y652160D02*
Y655503D01*
X357535Y658038D01*
X372200D01*
X374200Y656038D01*
Y645871D01*
G01X369273D02*
X374200D01*
G01X370200Y636400D02*
X371500D01*
X374200Y639100D01*
Y645871D01*
G01X350756Y656555D02*
Y657320D01*
X354102Y660666D01*
G01X387733Y598040D02*
X386273Y599500D01*
X384400D01*
X383300Y600600D01*
G01X391150Y610300D02*
Y613429D01*
G01X346465Y703185D02*
X347968D01*
X348533Y702620D01*
X350280D01*
G01X388720Y697180D02*
X392400D01*
X392720Y697500D01*
G01X384220Y700618D02*
X385220Y699618D01*
Y697180D01*
G01X380329Y696471D02*
X381038Y697180D01*
X385220D01*
G01X360500Y702460D02*
X353940D01*
X353780Y702620D01*
G01X456569Y-65072D02*
Y-145072D01*
G01X463200Y59150D02*
Y67984D01*
X475246Y80030D01*
X480287D01*
X483057Y82800D01*
X500250D01*
X503550Y79500D01*
G01X477400Y69300D02*
X477300Y69200D01*
Y64750D01*
G01X482350Y67973D02*
X481042D01*
X479715Y69300D01*
X477400D01*
G01X594069Y-65072D02*
Y-145072D01*
G01X563375Y68750D02*
X566750D01*
X568000Y70000D01*
G01X559200Y40550D02*
Y36265D01*
G01X580000Y64550D02*
X582400Y66950D01*
Y78600D01*
X584550Y80750D01*
G01X559200Y44050D02*
Y47200D01*
X559600Y47600D01*
G01X562750Y82000D02*
X567600D01*
X571000Y85400D01*
X582300D01*
X584550Y83150D01*
Y80750D01*
G01X599998Y386961D02*
Y391270D01*
G01X596077Y369579D02*
X596950Y370452D01*
Y373300D01*
G01X610160Y521543D02*
X603860D01*
X602860Y522543D01*
G01Y528543D02*
Y522543D01*
G01X650095Y391494D02*
X654670D01*
G01X614000Y337350D02*
Y334230D01*
X613480Y333710D01*
G01X633800Y337950D02*
X631250D01*
X629900Y339300D01*
G01X626772Y371336D02*
Y368128D01*
G01X634661Y370806D02*
X637000Y373145D01*
Y373856D01*
G01X633772Y375305D02*
X635551D01*
X637000Y373856D01*
G01X659300Y373100D02*
Y366032D01*
X653449Y360181D01*
G01X639067Y358541D02*
X651809D01*
X653449Y360181D01*
G01X609240Y370337D02*
X609087D01*
Y370827D01*
X607758Y372156D01*
Y373437D01*
G01X614000Y340850D02*
X614750D01*
X616900Y343000D01*
G01X667400Y359200D02*
X649650Y341450D01*
X633800D01*
G01X662150Y443200D02*
X657900D01*
G01X660000Y436900D02*
X655100D01*
G01X637147Y400247D02*
Y405815D01*
X636963Y405999D01*
G01X646469Y420936D02*
X637941D01*
X632180Y415175D01*
Y401800D01*
G01D02*
Y397968D01*
G01X640160Y521793D02*
X639910Y521543D01*
X635660D01*
G01X640160Y517269D02*
Y521793D01*
G01X671100Y470684D02*
X666216D01*
G01X618100Y555400D02*
X621453D01*
X621910Y554943D01*
G01D02*
Y550030D01*
X620160Y548280D01*
Y544793D01*
G01X650100Y540300D02*
X653600D01*
G01X619400Y567250D02*
Y570451D01*
G01X628160Y565543D02*
Y569095D01*
G01X659200Y549200D02*
X655500D01*
G01D02*
X651400Y545100D01*
G01X644100Y540300D02*
Y542400D01*
X645400Y543700D01*
Y545100D01*
G01X644100Y540300D02*
X644000Y540200D01*
X639800D01*
X639500Y540500D01*
G01X709069Y-65072D02*
Y-145072D01*
G01X727150Y187800D02*
Y184550D01*
G01X722150Y187800D02*
Y184550D01*
G01X711150Y177550D02*
Y174300D01*
G01X716650Y187800D02*
Y184550D01*
G01X711150Y187800D02*
Y184550D01*
G01X705650Y187800D02*
Y184550D01*
G01X725678Y176942D02*
X724792D01*
X722150Y174300D01*
G01X734028Y178896D02*
X730704D01*
X730550Y179050D01*
G01X732000Y188950D02*
Y185900D01*
G01X716650Y177550D02*
Y174400D01*
G01X696470Y197740D02*
X694890Y199320D01*
X693800D01*
X692800Y200320D01*
Y201100D01*
X692600Y201300D01*
G01X696050Y207600D02*
X691600D01*
G01X696550Y244800D02*
Y241550D01*
X696600Y241500D01*
G01X685050Y255400D02*
X683800D01*
X682030Y253630D01*
G01X685150Y259500D02*
Y255500D01*
X685050Y255400D01*
G01X685497Y269230D02*
Y265153D01*
X685550Y265100D01*
G01X682030Y253630D02*
X681950Y253550D01*
Y249100D01*
G01X681592Y244547D02*
Y248742D01*
X681950Y249100D01*
G01X681397Y240430D02*
X681592Y240625D01*
Y244547D01*
G01X693850Y228400D02*
X692900D01*
X690600Y230700D01*
G01D02*
X692300Y232400D01*
X693850D01*
G01Y236850D02*
Y232400D01*
G01X695953Y211743D02*
X691243D01*
G01X696100Y203560D02*
X694860D01*
X692600Y201300D01*
G01X714090Y328290D02*
Y329640D01*
X712410Y331320D01*
G01X706000Y328250D02*
X703650D01*
X702250Y329650D01*
G01X682750Y307000D02*
X673900D01*
X669950Y310950D01*
G01X685497Y269230D02*
Y273430D01*
G01D02*
Y277530D01*
G01Y281730D02*
Y277530D01*
G01X685350Y285900D02*
X685497Y285753D01*
Y281730D01*
G01X685350Y285900D02*
X683400D01*
X681800Y287500D01*
Y287950D01*
G01X731400Y359450D02*
Y362700D01*
G01X727000Y349750D02*
Y353000D01*
G01X711700Y348750D02*
Y352083D01*
X712417Y352800D01*
G01X718000Y349750D02*
Y353000D01*
G01X708000Y451500D02*
Y446100D01*
X708300Y445800D01*
G01X708000Y457500D02*
X703800D01*
X699900Y453600D01*
G01X688600Y485841D02*
X683583D01*
G01X672750Y485625D02*
X677275D01*
G01X702460Y481100D02*
Y476840D01*
X702824Y476476D01*
G01X679200Y462750D02*
X681750D01*
X682400Y463400D01*
G01X689000Y503250D02*
Y507800D01*
X689100Y507900D01*
G01X696700Y473350D02*
Y476000D01*
X696800Y476100D01*
Y476400D01*
G01X724900Y488000D02*
Y484930D01*
X726211Y483619D01*
G01X724900Y488000D02*
X720200D01*
G01X726211Y483619D02*
X726940Y482890D01*
X731594D01*
G01X672450Y503900D02*
X672500Y503950D01*
Y507100D01*
G01X695950Y504000D02*
Y508350D01*
X696000Y508400D01*
G01X719626Y594029D02*
Y590829D01*
G01X709200Y558300D02*
Y555393D01*
X710459Y554134D01*
G01X675676Y579571D02*
X669294D01*
G01X676194Y586179D02*
X670617D01*
X669202Y584764D01*
Y579663D01*
X669294Y579571D01*
G01X722300Y603700D02*
Y608200D01*
G01X707826Y604929D02*
Y607726D01*
X708600Y608500D01*
G01X719626Y598329D02*
X720726Y599429D01*
X722963D01*
X723369Y599835D01*
G01X790875Y66750D02*
X795832D01*
G01X776200Y51250D02*
Y47700D01*
X776300Y47600D01*
G01X777550Y66000D02*
Y62350D01*
G01X777700Y74150D02*
Y70601D01*
X774050Y66951D01*
Y66000D01*
G01X769812Y53660D02*
X774050Y57898D01*
Y66000D01*
G01X779400Y54750D02*
X776200D01*
G01X769450Y113000D02*
X772700D01*
G01X790625Y86050D02*
X794650D01*
G01X793957Y113436D02*
X792811D01*
X789475Y110100D01*
G01X784161Y126865D02*
X779594D01*
G01X781250Y101750D02*
X781355D01*
X782355Y102750D01*
X784400D01*
G01X765950Y113000D02*
X762000D01*
G01X758100Y188350D02*
Y185574D01*
X754725Y182199D01*
X754499D01*
X753800Y181500D01*
G01X741300Y188750D02*
Y185700D01*
G01X754000Y188750D02*
Y186000D01*
X753400Y185400D01*
G01X745700Y188950D02*
Y185900D01*
G01X775500Y188250D02*
Y186100D01*
X772700Y183300D01*
G01X749900Y188650D02*
Y185200D01*
G01X762200Y188750D02*
X768150D01*
X769100Y187800D01*
G01X737000Y188950D02*
Y185900D01*
G01X738465Y349685D02*
Y352935D01*
G01X744580Y452700D02*
Y455800D01*
X742700Y457680D01*
G01X757099Y526516D02*
Y530082D01*
G01X794088Y512162D02*
X797323D01*
G01X768500Y483800D02*
Y480000D01*
G01X785234Y505600D02*
X782000D01*
G01X771184Y518500D02*
Y514916D01*
G01X753099Y526516D02*
Y530282D01*
G01X795922Y526358D02*
Y531500D01*
G01X755800Y478184D02*
X758100D01*
G01X762400Y478900D02*
X759800D01*
X759084Y478184D01*
X758100D01*
G01X759200Y504250D02*
Y508000D01*
G01X777084Y523000D02*
Y518666D01*
X777250Y518500D01*
G01D02*
Y512550D01*
X777600Y512200D01*
G01X763809Y532000D02*
Y537191D01*
G01X782709Y532500D02*
Y537691D01*
G01X822470Y57425D02*
X826925D01*
G01X841300Y57830D02*
Y54200D01*
G01X823250Y322500D02*
Y319350D01*
G01X814484Y389702D02*
X814452Y389734D01*
X810946D01*
G01X814522Y393639D02*
X811208D01*
X811112Y393735D01*
G01X857569Y388383D02*
Y391421D01*
X857581Y391433D01*
G01X817984Y389702D02*
X818016Y389670D01*
X825300D01*
X826170Y388800D01*
X830300D01*
G01X817984Y389702D02*
Y385984D01*
X817700Y385700D01*
G01X861000Y406850D02*
Y410500D01*
G01X851100Y407500D02*
X850300Y406700D01*
Y403800D01*
G01X857000Y406850D02*
Y410600D01*
G01X821050Y527254D02*
Y533350D01*
G01X813150Y527254D02*
Y533450D01*
G01X800388Y523156D02*
Y526488D01*
X800800Y526900D01*
G01X809384Y480900D02*
Y484984D01*
G01X805249Y523327D02*
Y525919D01*
X804584Y526584D01*
G01X876569Y-65072D02*
Y-145072D01*
G01X896969Y301500D02*
X898310D01*
X900519Y299291D01*
X901219D01*
G01X885568Y322091D02*
X885577Y322100D01*
X888668D01*
G01X869000Y403400D02*
X872750D01*
G01X1046569Y-65072D02*
Y-145072D01*
G01X1244069Y-65072D02*
Y-145072D01*
G01X1272069Y-49072D02*
G02I-12000J0D01*
G01X1266919D02*
G02I-6850J0D01*
G01X1276069D02*
X1244069D01*
G01X1260069Y-65072D02*
Y-33072D01*
X77780Y61790D03*
X73760Y67930D03*
X56960Y58900D03*
X54050Y63260D03*
X43510Y57810D03*
X29890Y54070D03*
X49460Y63690D03*
X68730Y67930D03*
X38590Y55260D03*
X30270Y48330D03*
X31100Y458733D03*
X26576Y457406D03*
X34132Y521245D03*
X34175Y526969D03*
X64277Y502177D03*
X75399Y502179D03*
X69904Y502077D03*
X41250Y494600D03*
X53524Y521269D03*
Y526995D03*
X75405Y521695D03*
X69778D03*
X64151D03*
X49600Y496050D03*
X55300Y495600D03*
X62276Y550493D03*
X28800Y549474D03*
X29158Y543855D03*
X29058Y538228D03*
X28782Y555119D03*
X29165Y532612D03*
X33697Y560866D03*
X37660Y566400D03*
X42597Y571789D03*
X71002Y577013D03*
X67853Y573865D03*
X75197Y572437D03*
X64701Y570716D03*
Y564416D03*
X67853Y558117D03*
X61100Y546700D03*
X64400Y539000D03*
X67852Y586463D03*
Y583313D03*
X74151Y545516D03*
X74498Y551757D03*
X71002Y539219D03*
X74076Y535966D03*
X75508Y542198D03*
X71002Y542368D03*
X67852Y539219D03*
X71002Y545518D03*
Y558117D03*
X74152Y567565D03*
X71002D03*
Y564396D03*
X74152Y580163D03*
Y577013D03*
X71002Y561266D03*
X67853Y564416D03*
X75066Y563235D03*
X71002Y554967D03*
X67853D03*
X78276Y545566D03*
X67853Y542368D03*
X71002Y548668D03*
X52408Y543876D03*
X64701Y542366D03*
X52603Y549526D03*
X52485Y555153D03*
X53300Y560879D03*
X67853Y570715D03*
X74152Y583312D03*
X64703Y586463D03*
X63456Y555041D03*
X64701Y567566D03*
Y561266D03*
X67853D03*
Y577015D03*
X53524Y532622D03*
X52613Y538242D03*
X53302Y567317D03*
X59200Y582200D03*
X64884Y650984D03*
X38550Y617950D03*
X50700Y664000D03*
X50800Y667900D03*
X40309Y660700D03*
X71850Y698900D03*
X47150Y665500D03*
X76100Y697100D03*
X97600Y54810D03*
X84610Y64470D03*
X98770Y60860D03*
X89070Y62600D03*
X114390Y453185D03*
X102250Y455000D03*
X108300Y435900D03*
X118108Y453159D03*
X121826Y453156D03*
X128968Y452741D03*
X125353Y452385D03*
X132109Y451199D03*
X136021Y451394D03*
X127812Y445066D03*
X107100Y497300D03*
X97926Y502300D03*
X86699D03*
X81094Y502166D03*
X138900Y525999D03*
X135012Y510200D03*
X119400Y511500D03*
X132100Y493000D03*
X133152Y484074D03*
X105350Y511850D03*
X114070Y481948D03*
X117200Y495200D03*
X105920Y477098D03*
X141980Y508590D03*
X97637Y492891D03*
X118900Y522000D03*
X138000Y485900D03*
X102700Y507100D03*
X116500Y477000D03*
X144500Y489500D03*
X92286Y521695D03*
X81032D03*
X86659D03*
X97913D03*
X114500Y490000D03*
X101800Y493000D03*
X137050Y476346D03*
X132774Y497000D03*
X89899Y558115D03*
X86750Y573864D03*
X89899D03*
X86750Y567565D03*
X89899Y564415D03*
X106272Y547370D03*
X94473Y547093D03*
X89901Y587466D03*
X93048Y577014D03*
X108371Y577258D03*
X136990Y535235D03*
X86750Y542368D03*
X126337Y554085D03*
X130311Y546700D03*
X81276Y548766D03*
X119605Y548705D03*
X86750Y539218D03*
X83600Y545518D03*
X89899D03*
X127300Y543200D03*
X89899Y539218D03*
X117200Y546300D03*
X83600Y539219D03*
X86750Y545518D03*
X122600Y557480D03*
X86750Y554965D03*
X130607Y569636D03*
X86750Y558115D03*
X126347Y569556D03*
X83600Y551817D03*
X117400Y567650D03*
X83600Y573865D03*
X86750Y586463D03*
Y583313D03*
X83601Y580164D03*
X89899Y577014D03*
X86750D03*
X83600Y564415D03*
X86750D03*
X83600Y561265D03*
X96570Y581730D03*
X86750Y551815D03*
X123300Y530300D03*
X133800Y528500D03*
X123200Y534600D03*
X143500Y529000D03*
X93744Y542019D03*
X133554Y537374D03*
X93051Y587466D03*
X83600Y567565D03*
X93049Y573864D03*
X89899Y567565D03*
X93048Y580164D03*
X89899Y561265D03*
X86750D03*
X94720Y557158D03*
X92600Y535623D03*
X96371Y534124D03*
X101400Y606300D03*
X97800D03*
X137210Y622030D03*
X134030Y620760D03*
X130630Y620900D03*
X101500Y597000D03*
X85500Y628500D03*
X122750Y616950D03*
X122000Y628700D03*
X144800Y657900D03*
X136100Y656300D03*
X125100Y656700D03*
X123370Y606700D03*
X119600D03*
X118500Y638100D03*
X140700Y657700D03*
X130800Y656100D03*
X127401Y606930D03*
X123500Y613100D03*
X93053Y606734D03*
X142447Y611714D03*
X119000Y633200D03*
X120500Y651800D03*
X134650Y612900D03*
X144750Y606350D03*
X141971Y624700D03*
X98200Y616900D03*
X129800Y630700D03*
X105600Y597000D03*
X105400Y601300D03*
X104600Y609900D03*
X105600Y605900D03*
X104600Y614000D03*
X104500Y618800D03*
X117050Y602000D03*
X116200Y611600D03*
X116023Y607423D03*
X119400Y614100D03*
X116500Y621000D03*
X116400Y616900D03*
X130800Y606700D03*
X138500Y637900D03*
X130500Y638600D03*
X134700D03*
X129903Y634500D03*
X111300Y705500D03*
X107100Y679600D03*
X106879Y707245D03*
X125376Y701124D03*
X106355Y710745D03*
X106635Y701465D03*
X87683Y698924D03*
X84600Y688000D03*
X119849Y709715D03*
X146301Y460200D03*
X186602Y459767D03*
X197085Y459899D03*
X190278Y459865D03*
X193686Y459799D03*
X176000Y460200D03*
X172200Y460100D03*
X157496Y461248D03*
X166600Y509800D03*
X166700Y499800D03*
X146263Y468562D03*
X203307Y506400D03*
X179000Y499800D03*
X203500Y513500D03*
X186735Y463748D03*
X207500Y503000D03*
X191418Y509981D03*
X170870Y492270D03*
X158000Y480700D03*
X146143Y481057D03*
X175100Y477000D03*
X208370Y491570D03*
X183100Y499800D03*
X170838Y481762D03*
X146300Y502600D03*
X146112Y509412D03*
X158100Y493000D03*
X158400Y513600D03*
X155001Y513707D03*
X182874Y513591D03*
X178869Y513593D03*
X174900Y499800D03*
X166600Y513600D03*
X170700D03*
X172370Y463798D03*
X187000Y468000D03*
X146293Y464338D03*
X146193Y476938D03*
X146293Y472738D03*
X186600Y477700D03*
X187000Y499500D03*
X146500Y492500D03*
X183300Y493100D03*
X145400Y524046D03*
X176100Y473200D03*
X174700Y513900D03*
X182300Y509600D03*
X184780Y526990D03*
X187167Y513167D03*
X191100Y513367D03*
X154500Y487000D03*
X178869Y509793D03*
X209800Y478500D03*
X205447Y487762D03*
X158290Y502380D03*
X182874Y523590D03*
X205516Y467968D03*
X170700Y509800D03*
X170900Y500000D03*
X165900Y524100D03*
X209256Y467946D03*
X172100Y467300D03*
X176800Y492200D03*
X175805Y524073D03*
X206180Y509524D03*
X191100Y526000D03*
X195149Y513751D03*
X150500Y493000D03*
X190950Y482100D03*
X196200Y482600D03*
X200100Y491700D03*
X146216Y486045D03*
X196243Y486782D03*
X159480Y506590D03*
X155540Y506510D03*
X195300Y498900D03*
X195379Y510158D03*
X150162Y525937D03*
X148527Y519491D03*
X191725Y523074D03*
X195300Y529400D03*
X148409Y575672D03*
X144876Y590854D03*
X148409Y579353D03*
X144876Y587173D03*
X175100Y529100D03*
X203610Y529397D03*
X168390Y532060D03*
X184830Y529960D03*
X149419Y535654D03*
X191200Y529400D03*
X199400D03*
X208000Y529300D03*
X149242Y531080D03*
X152584Y532922D03*
X152415Y540014D03*
X194490Y645390D03*
X171020Y611020D03*
X200610Y639611D03*
X207900Y645600D03*
X169000Y640300D03*
X184967Y643983D03*
X200560Y635100D03*
X170940Y614400D03*
X191110Y611050D03*
X191370Y608190D03*
X208700Y625149D03*
X200879Y614739D03*
X145900Y641300D03*
X164800Y640200D03*
X173000Y640400D03*
X193610Y640040D03*
X189500Y639700D03*
X178140Y630330D03*
X196249Y630091D03*
X199400Y628646D03*
X151550Y629800D03*
X163200Y610070D03*
X160420Y610170D03*
X184050Y629500D03*
X181176Y627600D03*
X209093Y615849D03*
X166690Y615060D03*
X166600Y617850D03*
X195900Y649350D03*
X203400Y649600D03*
X146800Y629900D03*
X180700Y640460D03*
X204800Y617440D03*
X204642Y621140D03*
X177300Y626800D03*
X204150Y645180D03*
X199600Y650100D03*
X192960Y628510D03*
X187900Y628500D03*
X152700Y640800D03*
X161000Y634300D03*
X157200Y634200D03*
X196855Y698355D03*
X151130Y703440D03*
X148249Y695765D03*
X191766Y679920D03*
X202800Y660900D03*
X189000Y659900D03*
X206700Y695400D03*
X162100Y711215D03*
X151949Y691715D03*
X175233Y704382D03*
X163349Y702715D03*
X150849Y710215D03*
X163260Y706988D03*
X169070Y696220D03*
X159519Y694455D03*
X193500Y663000D03*
X200400Y694700D03*
X196900Y661350D03*
X206300Y661100D03*
X181300Y679100D03*
X185100Y705600D03*
X184800Y709300D03*
X190200Y671000D03*
X187500Y673100D03*
X272000Y461800D03*
X268350Y461950D03*
X275100Y460300D03*
X259000Y453900D03*
X251700Y443600D03*
X268900Y445150D03*
X244700Y451200D03*
X236100Y445100D03*
X239300Y443800D03*
X243000D03*
X247900Y445300D03*
X260600Y442600D03*
X250500Y451300D03*
X224500Y445600D03*
X254900Y453900D03*
X232200Y445600D03*
X275500Y466200D03*
X211700Y513500D03*
X220100Y513400D03*
X211196Y487762D03*
X222600Y503500D03*
X246000Y516670D03*
X275700Y490300D03*
X244900Y527300D03*
X228150Y525750D03*
X275400Y470300D03*
X213100Y476300D03*
X261200Y525400D03*
X242500Y523500D03*
X254500Y509600D03*
X213100Y472900D03*
X275200Y474500D03*
X258100Y516400D03*
X227500Y512200D03*
X265148Y524595D03*
X228700Y490717D03*
X230700Y486658D03*
X249050Y527150D03*
X249640Y495080D03*
X234700Y490900D03*
X258381Y509498D03*
X225914Y523051D03*
X231800Y512100D03*
X223600Y512400D03*
X213359Y480489D03*
X238400Y511300D03*
X265274Y509512D03*
X267800Y479900D03*
X222500Y536161D03*
X211500Y529400D03*
X230900Y581600D03*
X229800Y593200D03*
X247400Y589600D03*
X252593Y547650D03*
X261900Y591300D03*
X247100Y582400D03*
X246611Y551511D03*
X246484Y537139D03*
X269900Y567619D03*
X245743Y546963D03*
X270021Y549394D03*
X257000Y548400D03*
X263216Y554697D03*
X254530Y564300D03*
X251446Y553754D03*
X254500Y579500D03*
X273500Y567400D03*
X254300Y586500D03*
X273400Y590902D03*
X231434Y562844D03*
X234300Y582300D03*
X231200Y576800D03*
X231000Y571900D03*
X257300Y537500D03*
X214900Y529400D03*
X234943Y565199D03*
X254600Y567700D03*
X260731Y561264D03*
X260741Y542700D03*
X264333Y528926D03*
X254905Y555761D03*
X258528Y555161D03*
X259100Y567706D03*
X257000Y571700D03*
X223900Y531200D03*
X228100Y545500D03*
X228800Y542100D03*
X228313Y552169D03*
X262000Y586900D03*
X257851Y580080D03*
X270145Y557526D03*
X261308Y583388D03*
X237100Y590000D03*
X257700Y586400D03*
X261500Y576400D03*
X261600Y580000D03*
X257891Y563786D03*
X257600Y576500D03*
X233607Y557671D03*
X254500Y575070D03*
X261100Y571600D03*
X234800Y572000D03*
X232400Y533200D03*
X248900Y545700D03*
X267957Y537304D03*
X274623Y578896D03*
X271357Y537253D03*
X233036Y550942D03*
X213800Y631200D03*
X212308Y605949D03*
X229796Y610104D03*
X270000Y602400D03*
X255228Y631071D03*
X255648Y626127D03*
X245300Y635700D03*
X254199Y603443D03*
X254600Y597100D03*
X229137Y634881D03*
X266857Y634343D03*
X256001Y612347D03*
X258869Y603050D03*
X266571Y608619D03*
X275470Y608480D03*
X270400Y622870D03*
X264040Y648370D03*
X219200Y647200D03*
X221900Y630800D03*
X218800Y635600D03*
X230900Y649100D03*
X211706Y645349D03*
X247725Y656375D03*
X246500Y601500D03*
X234000Y629576D03*
X218200Y651400D03*
X248450Y609900D03*
X266847Y626253D03*
X229063Y638560D03*
X216600Y658400D03*
X274800Y635000D03*
X222950Y647900D03*
X255570Y616631D03*
X258962Y616384D03*
X236000Y647400D03*
X225900Y630700D03*
X231500Y659100D03*
X228149Y600094D03*
X242710Y604620D03*
X226471Y649129D03*
X243322Y597509D03*
X251314Y598106D03*
X251338Y601506D03*
X258550Y606527D03*
Y610096D03*
X215606Y645806D03*
X229500Y631500D03*
X212900Y619201D03*
X273714Y629870D03*
X266571Y630071D03*
X245100Y647200D03*
X272200Y648550D03*
X221238Y620524D03*
X234205Y598743D03*
X233258Y595693D03*
X232130Y612950D03*
X251900Y609600D03*
X259777Y638873D03*
X242000Y656400D03*
X255733Y622329D03*
X253196Y706062D03*
X261248Y700086D03*
X272050Y711810D03*
X267880Y704920D03*
X262634Y711233D03*
X266400Y675349D03*
X265000Y662574D03*
X247825Y670375D03*
X235100Y679921D03*
X221575Y695400D03*
X242000Y693400D03*
X255050Y675750D03*
X254800Y689400D03*
X269200Y699600D03*
X258423Y711343D03*
X268520Y719420D03*
X270900Y667200D03*
X237509Y674915D03*
X266200Y679400D03*
X268384Y662909D03*
X263700Y723500D03*
X264700Y700000D03*
X214270Y695095D03*
X275300Y668749D03*
X217638Y695562D03*
X235000Y692900D03*
X262323Y716917D03*
X255200Y680950D03*
X239400Y677900D03*
X266300Y692574D03*
X254648Y745463D03*
X311715Y20397D03*
X310353Y62159D03*
X326553Y34687D03*
X340297Y117548D03*
X341484Y110328D03*
X339232Y113960D03*
X338743Y122894D03*
X305700Y197600D03*
X295841Y176793D03*
X323582Y179064D03*
X299107Y177740D03*
X295462Y173414D03*
X304231Y265048D03*
Y261048D03*
X322426Y223731D03*
Y227531D03*
X321197Y254433D03*
X322426Y231331D03*
X321782Y215974D03*
X306446Y247874D03*
X305382Y227474D03*
X305498Y213824D03*
X305703Y202165D03*
X306407Y206057D03*
X335000Y226992D03*
X305782Y230874D03*
X335082Y231574D03*
X322301Y220009D03*
X305782Y217274D03*
X305682Y224074D03*
X305782Y220674D03*
X305454Y244461D03*
X334998Y255520D03*
X305373Y251101D03*
X334998Y259033D03*
X306412Y254339D03*
X335060Y262516D03*
X305882Y234274D03*
X305772Y237673D03*
X321700Y246000D03*
X321600Y250000D03*
X305781Y241076D03*
X334582Y291284D03*
Y287284D03*
Y283784D03*
Y279784D03*
X307567Y331592D03*
Y328092D03*
Y324092D03*
X304267Y322892D03*
Y318892D03*
Y315392D03*
Y311392D03*
X307567Y310292D03*
Y306292D03*
Y302792D03*
Y298792D03*
X304267Y297692D03*
Y293692D03*
Y290192D03*
Y286192D03*
X334582Y330271D03*
X328182Y329174D03*
Y325174D03*
Y321674D03*
Y317674D03*
X334582Y316574D03*
Y312574D03*
Y309074D03*
Y305074D03*
X328182Y303977D03*
Y299977D03*
Y296477D03*
Y292477D03*
X307567Y285092D03*
Y281092D03*
Y277592D03*
Y273592D03*
X304231Y272548D03*
Y268548D03*
X321281Y266486D03*
X321432Y279090D03*
X321882Y291874D03*
Y304374D03*
X321432Y316885D03*
Y329484D03*
X328913Y274414D03*
X334017Y272000D03*
X337808Y288709D03*
X304267Y373292D03*
Y369292D03*
Y365792D03*
Y361792D03*
X307567Y360692D03*
Y356692D03*
Y353192D03*
Y349192D03*
X304267Y348092D03*
Y344092D03*
Y340592D03*
Y336592D03*
X307567Y335592D03*
X328182Y379518D03*
Y375518D03*
Y372018D03*
Y368018D03*
X334582Y366974D03*
Y362974D03*
Y359474D03*
Y355474D03*
Y341771D03*
Y337771D03*
Y334271D03*
X328182Y354371D03*
Y350371D03*
Y346871D03*
Y342871D03*
X321432Y342082D03*
Y354681D03*
X321202Y376887D03*
X321432Y367279D03*
X335982Y390874D03*
X334000Y382700D03*
X303680Y380972D03*
X316900Y384100D03*
X319679Y387121D03*
X314000Y390500D03*
X335800Y379800D03*
X338800Y435100D03*
X281200Y453500D03*
X333850Y458400D03*
X286700Y457500D03*
X323759Y435145D03*
X327159Y435201D03*
X276634Y498311D03*
X307364Y505750D03*
X321976D03*
X329035Y519325D03*
X293793Y521556D03*
X321208Y519411D03*
X325136Y519316D03*
X333922Y527323D03*
X340961Y511600D03*
X298335Y521458D03*
X304800Y512800D03*
X286797Y516522D03*
X308687Y519193D03*
X302307Y505799D03*
X298907Y505851D03*
X292100Y516000D03*
X297400Y517981D03*
X336600Y504500D03*
X336800Y499967D03*
X325400Y505800D03*
X282403Y474500D03*
X282400Y470200D03*
X328200Y511600D03*
X331200Y508900D03*
X299448Y511300D03*
X277603Y479948D03*
X332821Y515415D03*
X278400Y463300D03*
X280939Y504705D03*
X314400Y505750D03*
X334650Y508900D03*
X300476Y546907D03*
X285800Y549394D03*
X303100Y587000D03*
X292850Y586100D03*
X293271Y557248D03*
X327110Y583660D03*
X316680Y583527D03*
X337899Y587874D03*
X285982Y542502D03*
X310350Y538293D03*
X330860Y551744D03*
X325447Y536109D03*
X325774Y547428D03*
X331700Y587896D03*
X303520Y550085D03*
X296835Y591015D03*
X280646Y557150D03*
X303500Y582200D03*
X333847Y531105D03*
X286195Y530579D03*
X291800Y576708D03*
X333800Y534830D03*
X329840Y572710D03*
X337550Y534619D03*
X295824Y578108D03*
X325475Y572818D03*
X323659Y557310D03*
X334900Y586100D03*
X333512Y553888D03*
X281610Y590260D03*
X324200Y565300D03*
X281490Y586862D03*
X337300Y583000D03*
X336367Y549943D03*
X294107Y560762D03*
X330729Y557268D03*
X298000Y561000D03*
X327059Y557247D03*
X288309Y566467D03*
X328580Y568120D03*
X291000Y570810D03*
X320954Y572631D03*
X277048Y590470D03*
X319529Y562413D03*
X319252Y566509D03*
X285912Y538750D03*
X318736Y549697D03*
X280100Y532100D03*
X322889Y529380D03*
X322843Y533254D03*
X279664Y535473D03*
X328771Y549035D03*
X332808Y547575D03*
X332834Y543993D03*
X337346Y545100D03*
X341316Y545000D03*
X282000Y583500D03*
X298514Y550184D03*
X293087Y530571D03*
X325687Y551368D03*
X319430Y557486D03*
X276839Y582309D03*
X277441Y539882D03*
X308200Y593153D03*
X310292Y532128D03*
X339081Y628173D03*
X290300Y636900D03*
X290500Y640600D03*
X331655Y603405D03*
X339822Y609785D03*
X339847Y620281D03*
X305470Y623734D03*
X278546Y633450D03*
X281900Y640900D03*
X317600Y603300D03*
X339266Y658409D03*
X278443Y648857D03*
X284495Y613130D03*
X286700Y622190D03*
X340100Y631417D03*
X339751Y616882D03*
Y613185D03*
X335036Y603039D03*
X338733D03*
X325300Y648700D03*
X294500Y630600D03*
X298100Y630650D03*
X330400Y644300D03*
X334700Y644500D03*
X302459Y599531D03*
X306100Y599500D03*
X306231Y602898D03*
X302180Y603084D03*
X335100Y650600D03*
X338100Y635800D03*
X331718Y655832D03*
X329100Y650700D03*
X317689Y599833D03*
X287200Y632600D03*
X290900Y630900D03*
X278769Y700697D03*
X318400Y678400D03*
X325900Y678500D03*
X281400Y708200D03*
X281500Y712200D03*
X279400Y686400D03*
X294804Y695204D03*
X296800Y665081D03*
X311600Y670354D03*
X319600Y670450D03*
X293300Y679700D03*
X321800Y678500D03*
X281000Y678000D03*
X304400Y665100D03*
X316465Y716063D03*
X340500Y711750D03*
X335750Y664700D03*
X288700Y667900D03*
X340100Y718200D03*
X327250Y701500D03*
X327162Y696776D03*
X282300Y700100D03*
X276800Y697925D03*
X338669Y691580D03*
X339804Y679030D03*
X340403Y699400D03*
X340300Y703100D03*
X336200Y677000D03*
X289700Y678830D03*
X280646Y717540D03*
X276100Y677700D03*
X300100Y670300D03*
X304700Y668500D03*
X298570Y743670D03*
X306470Y743570D03*
X278553Y740020D03*
X291700Y737000D03*
X287620Y737300D03*
X290000Y727000D03*
X313873Y735907D03*
X314100Y739300D03*
X380500Y33500D03*
Y30000D03*
X384000D03*
X381173Y49058D03*
X381156Y54116D03*
X375200Y63400D03*
X370870Y45605D03*
X368059Y57759D03*
X354798Y22452D03*
X375300Y72150D03*
X374844Y87900D03*
X375000Y107300D03*
X393206Y77614D03*
X374844Y76700D03*
X362000Y124000D03*
X386759Y79693D03*
X390456D03*
X342539Y120370D03*
X369253Y88733D03*
X367287Y77118D03*
X381269Y94981D03*
X384666Y93741D03*
X349206Y129948D03*
X390964Y87226D03*
X388700Y89800D03*
X349072Y193574D03*
X400212Y154732D03*
X400351Y165605D03*
X349072Y189774D03*
X371775Y200577D03*
X348082Y186224D03*
X370149Y167337D03*
X370882Y163688D03*
X387202Y164664D03*
X387393Y160859D03*
X404727Y162141D03*
X392102Y175384D03*
X400205Y158209D03*
Y161906D03*
X392458Y171676D03*
X400430Y147190D03*
X362197Y222068D03*
X362722Y237674D03*
X361792Y243154D03*
X372888Y208022D03*
X359882Y203458D03*
X347482Y254774D03*
X341882Y251064D03*
X342885Y276301D03*
X342958Y279701D03*
X383170Y329807D03*
X345582Y380874D03*
X344732Y393882D03*
Y390274D03*
X383285Y347114D03*
X383327Y343379D03*
X396561Y351418D03*
X346600Y375000D03*
X344732Y386874D03*
X365100Y348300D03*
X372491Y378025D03*
X365200Y344400D03*
X378492Y378175D03*
X383030Y352442D03*
X367358Y372531D03*
X367471Y369120D03*
X360100Y453500D03*
X342700Y435200D03*
X350491Y453809D03*
X372000Y452100D03*
X369900Y458700D03*
X387450Y454558D03*
X387396Y458126D03*
X384395Y449114D03*
X374700Y460300D03*
X350400Y459000D03*
X381106Y441241D03*
X350400Y462400D03*
X374650Y456771D03*
X346500Y435200D03*
X364500Y453700D03*
X367400Y461200D03*
X355400Y453800D03*
X357900Y450800D03*
X369000Y512700D03*
X345497Y527644D03*
X355300Y510100D03*
X353300Y521400D03*
X344700Y509000D03*
X368721Y525271D03*
X371900Y481548D03*
X365800Y498300D03*
X357450Y491450D03*
X364500Y525260D03*
X369300Y508700D03*
X344400Y505400D03*
X344500Y500300D03*
X363500Y464700D03*
X372000Y477710D03*
X355300Y502700D03*
X357700Y499000D03*
X400080Y500854D03*
X384849Y525499D03*
Y521681D03*
X355300Y506100D03*
Y513500D03*
X386367Y474700D03*
X400080Y519500D03*
Y491107D03*
Y523903D03*
Y528243D03*
X389349Y480100D03*
X381986Y515631D03*
X374751Y485636D03*
X374715Y498722D03*
X366950Y464700D03*
X390229Y508189D03*
X341500Y520400D03*
X373699Y521160D03*
X359100Y503200D03*
X374800Y516912D03*
X387450Y467000D03*
X389288Y483500D03*
X358800Y478000D03*
X373800Y503000D03*
X370900Y464700D03*
X378267Y496100D03*
X349088Y500296D03*
X373500Y540305D03*
X393912Y568499D03*
X351600Y540600D03*
X348314Y585614D03*
X385600Y529107D03*
X372600Y576207D03*
X374292Y580300D03*
X355012Y582324D03*
X363008Y547309D03*
X371227Y566830D03*
X384950Y560496D03*
X383000Y577000D03*
X386305Y581647D03*
X362700Y551200D03*
X361279Y581647D03*
X362100Y574700D03*
X349000Y581360D03*
X379050Y539931D03*
X341740Y535800D03*
X352279Y580294D03*
X346303Y591947D03*
X386723Y544565D03*
X342440Y571770D03*
X361900Y570800D03*
X369500Y542900D03*
X388641Y549747D03*
X400093Y536351D03*
X399726Y562327D03*
X399946Y558677D03*
X344163Y553395D03*
X345259Y557566D03*
X391993Y582154D03*
X362300Y555200D03*
X343840Y566440D03*
X348300Y565400D03*
X364900Y585171D03*
X364964Y588771D03*
X372939Y559838D03*
X346590Y572090D03*
X350278Y572306D03*
X366270Y563400D03*
X373222Y535938D03*
X370247Y546218D03*
X370223Y549965D03*
X384950Y551876D03*
Y555276D03*
X383056Y563675D03*
X400060Y554743D03*
X393912Y571899D03*
X393910Y575305D03*
X341493Y541250D03*
X393912Y578705D03*
X348600Y643500D03*
X344564Y628104D03*
X379400Y641800D03*
X385163Y641354D03*
X342133Y603008D03*
X391150Y613429D03*
X350500Y647600D03*
X355000Y652160D03*
X374200Y645871D03*
X370200Y636400D03*
X359036Y635900D03*
X359258Y596820D03*
X383300Y600600D03*
X384410Y633530D03*
X348000Y612661D03*
X352720Y600970D03*
X367133Y596067D03*
X382380Y612277D03*
X352400Y626102D03*
X372408Y629626D03*
X364014Y593996D03*
X343797Y631417D03*
X381967Y616123D03*
X361227Y630300D03*
X377700Y595000D03*
X383199Y623168D03*
X382438Y608755D03*
X384158Y638105D03*
X380443D03*
X400064Y652598D03*
X384300Y619925D03*
X354102Y660666D03*
X392720Y697500D03*
X376342Y711260D03*
X358296Y672460D03*
X346465Y703185D03*
X364200Y713100D03*
X369600Y693400D03*
X351100Y712100D03*
X384220Y700618D03*
X367600Y696800D03*
X396166Y692630D03*
X343200Y667600D03*
X389999Y664697D03*
X367700Y685450D03*
X343338Y679236D03*
X399999Y673422D03*
X396419Y679708D03*
X398983Y706749D03*
X382308Y665022D03*
X396419Y686586D03*
X372350Y698400D03*
X399093Y703350D03*
X380300Y703000D03*
X399154Y699950D03*
X341900Y690350D03*
X346600Y714500D03*
X346000Y684300D03*
X383800Y688400D03*
X380387Y685261D03*
X392500Y673500D03*
X392800Y677600D03*
X341934Y662794D03*
X378595Y664960D03*
X388626Y715509D03*
X392500Y692500D03*
X355298Y711750D03*
X396419Y683186D03*
X459950Y58000D03*
X469058Y49156D03*
X439200Y22100D03*
X439549Y26339D03*
X439554Y30429D03*
X439302Y34040D03*
X458972Y49634D03*
X462625Y49881D03*
X467300Y20000D03*
X450454Y38147D03*
X448520Y49979D03*
X430800Y22200D03*
X433600Y19900D03*
X428001Y25269D03*
X433400Y63373D03*
X438600Y91033D03*
X419662Y71426D03*
X423340Y71621D03*
X469901Y94047D03*
X415211Y71263D03*
X461736Y111300D03*
X442800Y90934D03*
X496700Y32100D03*
X482693Y42200D03*
X478500Y19775D03*
X490050Y45900D03*
X506970Y18693D03*
X502830D03*
X477400Y69300D03*
X512806Y49494D03*
X473151Y50052D03*
X521200Y57600D03*
X496035Y46435D03*
X503814Y56676D03*
X515500Y57900D03*
X486568Y38006D03*
X486114Y41700D03*
X496430Y22890D03*
X491270Y18877D03*
X485674Y32924D03*
X524950Y16120D03*
X473172Y95508D03*
X479147Y102165D03*
X490100Y111300D03*
X486400Y74700D03*
X481800Y71200D03*
X513909Y85849D03*
X510408Y85779D03*
X559200Y36265D03*
X552540Y64530D03*
X599422Y51662D03*
X568430Y50010D03*
X596489Y14110D03*
X559600Y47600D03*
X575550Y42800D03*
X601311Y13521D03*
X569300Y66274D03*
X545200Y69000D03*
X596300Y66950D03*
X549550Y61900D03*
X597950Y58950D03*
X564500Y64100D03*
X573600Y49750D03*
X577100Y78600D03*
X545300Y75600D03*
X568000Y70000D03*
X584550Y80750D03*
X559900Y88400D03*
X563268Y88872D03*
X540179Y111036D03*
X539346Y114333D03*
X578900Y82500D03*
X551500Y82400D03*
X599682Y103715D03*
X547100Y79900D03*
X578400Y74500D03*
X562160Y178600D03*
X582219Y386612D03*
X599998Y391270D03*
X598964Y354128D03*
X596077Y369579D03*
X602075Y339970D03*
X586155Y393023D03*
X593064Y400910D03*
X593229Y397308D03*
X666535Y26149D03*
X665800Y7550D03*
X666400Y22200D03*
X638470Y164470D03*
X634910Y169360D03*
X644100Y199850D03*
X630000Y169600D03*
X629500Y187500D03*
X619980Y197550D03*
X634000Y187500D03*
X630800Y147600D03*
X634800Y147700D03*
X666700Y205600D03*
X629400Y217300D03*
X644100Y203350D03*
X634450Y252100D03*
X631550Y249850D03*
X625926Y247530D03*
X627200Y253550D03*
X625250Y264250D03*
X625550Y244150D03*
Y240750D03*
X645516Y225334D03*
X620750Y258050D03*
X642547Y226992D03*
X632958Y231000D03*
X633109Y234397D03*
X632900Y238000D03*
X628300Y230550D03*
X625700Y235750D03*
X640141Y259859D03*
X640400Y217600D03*
X636491Y217592D03*
X633092Y217496D03*
X659500Y205300D03*
X662900D03*
X645400Y264050D03*
X620160Y203500D03*
X648700Y292900D03*
X660700Y292200D03*
X634830Y292095D03*
X638453Y291949D03*
X633400Y274600D03*
X652850Y269600D03*
X642300Y276450D03*
X649000Y273500D03*
X652100Y279300D03*
X656700Y305607D03*
X664600Y306100D03*
X648700Y303600D03*
X652500Y305707D03*
X638603Y296320D03*
X642003Y296249D03*
X645403Y296229D03*
X631069Y292512D03*
X654670Y391494D03*
X616428Y379533D03*
X626772Y371336D03*
X612300Y344300D03*
X613480Y333710D03*
X629900Y339300D03*
X610300Y354800D03*
X654600Y367600D03*
X639318Y354003D03*
X643082Y353941D03*
X629239Y387969D03*
X620100Y384100D03*
X608600Y362600D03*
X659300Y373100D03*
X637000Y373856D03*
X632220Y389694D03*
X607800Y382362D03*
X607100Y351200D03*
X638360Y383805D03*
X642270Y383869D03*
X605400Y393400D03*
X618600Y364375D03*
X609240Y370337D03*
X616900Y343000D03*
X615150Y364200D03*
X640968Y370425D03*
X606626Y354723D03*
X637353Y379591D03*
X657900Y443200D03*
X655100Y436900D03*
X636963Y405999D03*
X632180Y397968D03*
X654300Y504100D03*
X613000Y463000D03*
X666216Y470684D03*
X632800Y561600D03*
X620160Y544793D03*
X610200Y555400D03*
X628160Y569095D03*
X619400Y570451D03*
X653600Y540300D03*
X635970Y557600D03*
X638660Y568043D03*
X616160Y542700D03*
X614000Y561250D03*
X606600Y551100D03*
X722150Y174300D03*
X727150Y184550D03*
X722150D03*
X711150Y174300D03*
X716650Y184550D03*
X711150D03*
X705650D03*
X677770Y196410D03*
X730550Y179050D03*
X732000Y185900D03*
X716650Y174400D03*
X674300Y198900D03*
X704579Y258164D03*
X721261Y240551D03*
X721260Y234252D03*
X730710Y256302D03*
X733858Y256299D03*
Y253149D03*
X730710Y253152D03*
X733859Y234253D03*
Y237403D03*
X730710D03*
Y234254D03*
X733858Y243700D03*
Y246849D03*
Y249999D03*
Y265747D03*
X730710Y240553D03*
Y243702D03*
Y246852D03*
Y250002D03*
Y265750D03*
X721295Y221651D03*
X718089Y243684D03*
X721260Y253150D03*
Y259449D03*
Y265748D03*
X721261Y246851D03*
X733859Y240552D03*
X727559Y259449D03*
Y265748D03*
Y253150D03*
Y240551D03*
X727560Y246851D03*
X727559Y221654D03*
Y234252D03*
X727594Y227950D03*
X696600Y241500D03*
X701500Y250564D03*
X691600Y207600D03*
X718121Y256326D03*
X718089Y246834D03*
X718098Y259423D03*
X718072Y265748D03*
X718089Y249984D03*
X718129Y253144D03*
X693800Y264300D03*
X725466Y200819D03*
X707923Y219765D03*
X708900Y214500D03*
X718111Y224802D03*
X706500Y212150D03*
X709615Y223228D03*
X718111Y231101D03*
X696300Y215750D03*
X702900Y212350D03*
X707679Y233664D03*
X718111Y227952D03*
X722322Y200935D03*
X704279Y226664D03*
X705529Y231064D03*
X705779Y236764D03*
X706079Y240664D03*
X710716Y235827D03*
X714945Y234230D03*
X726988Y204312D03*
X718123Y201101D03*
X710079Y203664D03*
X718895Y207125D03*
X705364Y205864D03*
X713168Y207689D03*
X718111Y221653D03*
X733859Y215355D03*
X718110Y234252D03*
X709679Y239164D03*
X727560Y215355D03*
X716116Y207469D03*
X718111Y237401D03*
X709079Y229564D03*
X703979Y219995D03*
X718111Y240550D03*
X711812Y243700D03*
X714961D03*
X730709Y215355D03*
X724410D03*
X732264Y204312D03*
X703320Y203900D03*
X733859Y212206D03*
X729800Y208400D03*
X730709Y221654D03*
X733858D03*
X724410D03*
Y234252D03*
Y240551D03*
Y246850D03*
Y253150D03*
Y227953D03*
Y265748D03*
Y259449D03*
X704579Y261964D03*
X682030Y253630D03*
X706100Y250000D03*
X690600Y230700D03*
X691243Y211743D03*
X692600Y201300D03*
X677800Y215900D03*
X724410Y281496D03*
X730710D03*
X733859D03*
Y275198D03*
X730710Y272048D03*
X733858Y268897D03*
X721820Y315750D03*
X730710Y268899D03*
X721260Y275196D03*
Y272047D03*
X733859Y278346D03*
X677300Y314900D03*
X681200D03*
X684400Y313400D03*
X688000Y313200D03*
X694675Y323900D03*
X730708Y290944D03*
X724409D03*
X727559Y272047D03*
Y278346D03*
X708100Y331410D03*
X718340Y315800D03*
X706796Y295829D03*
X726895Y309117D03*
X711799Y304234D03*
X713339Y306954D03*
X724063Y306305D03*
X698039Y285854D03*
X707834Y293060D03*
X707079Y286964D03*
X704079Y300964D03*
X719200Y307400D03*
X705579Y298464D03*
X695508Y288964D03*
X710679Y267894D03*
X721230Y284653D03*
X718099Y290964D03*
X710329Y285214D03*
X718117Y281465D03*
X718080Y284653D03*
X701708Y292364D03*
X706277Y279162D03*
X718072Y278346D03*
X708409Y276771D03*
X733892Y297246D03*
X730708Y297243D03*
X714619Y303884D03*
X692750Y293200D03*
X718109Y272034D03*
X694307Y283485D03*
X722468Y308964D03*
X727558Y297243D03*
X733859Y272048D03*
X690579Y299964D03*
X675555Y318736D03*
X672350Y317600D03*
X724409Y297243D03*
X700323Y283078D03*
X716300Y331340D03*
X733859Y284646D03*
X695300Y306700D03*
X718099Y287814D03*
X712410Y331320D03*
X702250Y329650D03*
X733857Y290944D03*
X727558D03*
X730300Y314900D03*
X724410Y272047D03*
Y278346D03*
Y284645D03*
X669950Y310950D03*
X681800Y287950D03*
X718137Y275186D03*
X702939Y281484D03*
X718109Y268934D03*
X714949Y287814D03*
X731400Y362700D03*
X727000Y353000D03*
X712417Y352800D03*
X718300Y362900D03*
X722500Y353000D03*
X718000D03*
X713500Y362900D03*
X729900Y393200D03*
X708300Y445800D03*
X709006Y410206D03*
X721504Y402321D03*
X699900Y453600D03*
X691813Y407210D03*
X691874Y410741D03*
X691873Y403800D03*
X690550Y453850D03*
X690300Y460200D03*
X720900Y412900D03*
X728874Y470860D03*
X725366Y470722D03*
X677275Y485625D03*
X683583Y485841D03*
X702824Y476476D03*
X682400Y463400D03*
X696800Y476400D03*
X689100Y507900D03*
X730600Y493100D03*
X716078Y492334D03*
X672500Y507100D03*
X696000Y508400D03*
X715391Y479109D03*
X703440Y548820D03*
X710459Y554134D03*
X719626Y590829D03*
X725000Y576100D03*
X714800Y567956D03*
X710000Y549100D03*
X710100Y545600D03*
X705176Y593429D03*
X717450Y551554D03*
X697200Y529200D03*
X705676Y562429D03*
X722300Y608200D03*
X708600Y608500D03*
X702515Y597064D03*
X693900Y597800D03*
X703800Y608400D03*
X712708Y603038D03*
X723369Y599835D03*
X722122Y611840D03*
X777550Y62350D03*
X795832Y66750D03*
X787360Y35650D03*
X776300Y47600D03*
X769812Y53660D03*
X756431Y54010D03*
X736803Y52087D03*
X779400Y54750D03*
X746500Y47200D03*
X780815Y47062D03*
X776600Y35250D03*
X762765Y42200D03*
X761900Y81700D03*
X772700Y113000D03*
X794650Y86050D03*
X769710Y125150D03*
X766110Y125270D03*
X793957Y113436D03*
X761950Y126450D03*
X773200Y97600D03*
X781250Y101750D03*
X779594Y126865D03*
X762000Y113000D03*
X763825Y89975D03*
X776500Y82700D03*
X750500Y118500D03*
X750600Y114200D03*
X769500Y91000D03*
X792600Y101300D03*
X772800Y107550D03*
X776850Y115050D03*
X749600Y199300D03*
X749400Y195600D03*
X753800Y181500D03*
X753400Y185400D03*
X741300Y185700D03*
X738160Y199480D03*
X749900Y185200D03*
X786343Y179959D03*
X745700Y185900D03*
X769100Y187800D03*
X786388Y183429D03*
X772810Y179901D03*
X772700Y183300D03*
X737000Y185900D03*
X765900Y191900D03*
X768579Y203964D03*
X764900Y207200D03*
X768505Y243702D03*
X784277Y243713D03*
X784253Y227953D03*
Y231103D03*
X752756Y234253D03*
Y231103D03*
Y224804D03*
Y227954D03*
X749606Y231103D03*
Y234253D03*
Y227954D03*
Y224804D03*
X737008Y256299D03*
X740158D03*
Y253149D03*
X737008D03*
X771655Y237402D03*
X765353D03*
X737009Y237400D03*
X737008Y243700D03*
Y246849D03*
Y249999D03*
Y265747D03*
X740158Y246849D03*
Y265747D03*
X740122Y243700D03*
X740158Y249999D03*
X752756Y221654D03*
X737008D03*
X771654Y253150D03*
X777954Y237402D03*
Y227953D03*
Y231103D03*
X765355Y265749D03*
X771654Y259449D03*
Y265749D03*
X793701Y221654D03*
X781103Y227954D03*
X784277Y246863D03*
X784267Y259426D03*
X746457Y224804D03*
X755906D03*
X737009Y227953D03*
Y234253D03*
Y231103D03*
X774804Y221655D03*
Y224804D03*
Y227954D03*
X746457D03*
X755906D03*
X746457Y231103D03*
X755906D03*
X746457Y234253D03*
X755906D03*
X759056Y253150D03*
X765355Y234253D03*
X765354Y231102D03*
X765355Y227953D03*
X765354Y246850D03*
X784277Y253162D03*
X740132Y240562D03*
X759055Y221654D03*
X765355Y224804D03*
X771654Y215355D03*
Y209056D03*
Y212205D03*
X746457Y240552D03*
X752757D03*
X759056D03*
X746421Y253149D03*
X749455Y202200D03*
X765354Y221654D03*
X743307D03*
X762205Y215355D03*
X781103Y237402D03*
Y231103D03*
X787402Y221654D03*
X787401Y215354D03*
X746457Y246850D03*
X752720Y253149D03*
X752757Y246851D03*
X765355Y253150D03*
X759056Y246851D03*
X746433Y265761D03*
X746457Y259449D03*
X752757D03*
Y265749D03*
X765355Y259449D03*
X759056Y265749D03*
X759031Y259461D03*
X777976Y265761D03*
X784267Y256276D03*
X793701Y231103D03*
X793672Y243709D03*
X799991Y249972D03*
X799972Y262588D03*
X796822D03*
Y256289D03*
X790551Y259486D03*
X790538Y265723D03*
X793701Y237402D03*
X777976Y259461D03*
X781102Y221654D03*
X749606D03*
X762205Y212205D03*
X761600Y207300D03*
X787402Y240552D03*
Y243701D03*
X793700Y256262D03*
X752759Y218499D03*
X755909Y218514D03*
X790550Y253150D03*
X799972Y256309D03*
X781080Y265763D03*
X784258Y262618D03*
X777967Y262576D03*
X790523Y256289D03*
X800021Y243717D03*
X795593Y206063D03*
X777953Y256300D03*
X781300Y207800D03*
X774803Y265749D03*
X737009Y240552D03*
X746457Y215355D03*
X737029Y215337D03*
X743279Y215364D03*
X740158Y215355D03*
X743279Y212196D03*
X741294Y208274D03*
X743008Y206059D03*
X765355Y240552D03*
X743307Y246850D03*
X762217Y240526D03*
X755880Y240563D03*
X749580D03*
X755869Y253149D03*
X762167Y246850D03*
X755907Y246851D03*
X749569Y246850D03*
X762168Y253149D03*
X749608Y253150D03*
X743282Y253161D03*
X755868Y265748D03*
X755882Y259461D03*
X762218Y259425D03*
X749582Y259461D03*
X743282D03*
X762181Y265762D03*
X749582Y265761D03*
X743282D03*
X743281Y240562D03*
X768480Y265762D03*
X768518Y259425D03*
X768467Y253149D03*
Y246850D03*
X771653Y246887D03*
X762205Y221654D03*
X784252D03*
X777953D03*
X790551D03*
X740158D03*
X755906D03*
X746457D03*
X793701Y234254D03*
X781127Y246863D03*
X793672Y240560D03*
X796821Y246859D03*
X793701Y227954D03*
X796850Y221654D03*
X793674Y265758D03*
X793699Y262634D03*
X768504Y215355D03*
X763963Y331837D03*
X766437Y329363D03*
X769266Y326534D03*
X748737Y330263D03*
X751566Y327434D03*
X762229Y290933D03*
X752756Y278346D03*
X759073Y287810D03*
X774826Y268910D03*
X737009Y281496D03*
X740159Y278345D03*
Y281496D03*
X759031Y275209D03*
X765356Y272048D03*
Y275197D03*
Y278347D03*
X740158Y275197D03*
Y272046D03*
X737008D03*
Y268897D03*
X740158D03*
X746457Y272047D03*
Y275197D03*
X752757D03*
X752731Y272060D03*
X762181D03*
X759031D03*
X762206Y275197D03*
Y278347D03*
X737009Y275196D03*
X790551Y284646D03*
X781100Y287800D03*
X787419Y278354D03*
X737007Y290944D03*
X749579Y297254D03*
X787402Y297243D03*
X781102Y297244D03*
X771654Y297243D03*
X759058Y300414D03*
X768503Y287794D03*
X774802D03*
X787400Y287795D03*
X749607Y275197D03*
X774789Y275174D03*
X784221Y284652D03*
X777915Y281496D03*
X762189Y281514D03*
X768489Y281474D03*
X777953Y275198D03*
Y278347D03*
X784290Y272047D03*
X743306Y290944D03*
X749606Y278346D03*
X749593Y284670D03*
X799999Y290944D03*
Y284645D03*
Y278345D03*
X799974Y272058D03*
X793701Y300393D03*
X790519Y272053D03*
X790550Y287795D03*
X749605Y290944D03*
X762204Y287794D03*
X781064Y272047D03*
X784243Y278318D03*
X780300Y309300D03*
X740157Y297243D03*
X737008Y297244D03*
X740158Y284646D03*
X744881Y309000D03*
X743306Y297243D03*
X790526Y300406D03*
X765369Y281474D03*
X771669D03*
X781120Y284665D03*
X759070Y281514D03*
X749816Y303716D03*
X777790Y304778D03*
X769768Y304464D03*
X759208Y304284D03*
X784252Y268885D03*
X796839Y290934D03*
X787438Y275197D03*
X796832Y272064D03*
X796875Y304331D03*
X796862Y281522D03*
X784249Y281464D03*
X787426Y272060D03*
X790551Y278384D03*
X743308Y284646D03*
X746457D03*
X737009D03*
X744400Y322800D03*
X746456Y297243D03*
X765353Y287794D03*
X771653D03*
X777952D03*
X784251D03*
X762225Y297227D03*
X755898Y287804D03*
X743283Y272060D03*
X755882D03*
X749581D03*
X746456Y290944D03*
X740157D03*
X793700Y297243D03*
X796849D03*
X790545Y290959D03*
X793694D03*
X793703Y287797D03*
X796839Y287784D03*
X793675Y284637D03*
X793679Y281508D03*
X793675Y278357D03*
X796868Y278364D03*
X793737Y275196D03*
X793682Y272064D03*
X793683Y268879D03*
X796850Y268910D03*
X799534Y339466D03*
X760252Y353266D03*
X763081Y350437D03*
X765555Y347963D03*
X768384Y345134D03*
X761134Y334666D03*
X772352Y341266D03*
X775181Y338437D03*
X777655Y335963D03*
X780484Y333134D03*
X777434Y353566D03*
X780263Y350737D03*
X782737Y348263D03*
X785566Y345434D03*
X789334Y341766D03*
X792163Y338937D03*
X794637Y336463D03*
X797466Y333634D03*
X743434Y335566D03*
X746263Y332737D03*
X749534Y346566D03*
X752363Y343737D03*
X754837Y341263D03*
X757666Y338434D03*
X795026Y374556D03*
X799426Y374456D03*
X738465Y352935D03*
X790357Y377781D03*
X735300Y401957D03*
X774700Y483600D03*
X794700Y505200D03*
X747125Y483924D03*
X743726Y483813D03*
X755500Y492600D03*
X768500Y480000D03*
X740253Y483893D03*
X797323Y512162D03*
X782000Y505600D03*
X771184Y514916D03*
X745700Y498250D03*
X742300Y498200D03*
X759000Y482900D03*
X759169Y497414D03*
X750600Y497400D03*
X759200Y508000D03*
X777600Y512200D03*
X781700Y510900D03*
X736600Y500000D03*
X780750Y496750D03*
X781050Y492550D03*
X757099Y530082D03*
X763809Y537191D03*
X782709Y537691D03*
X753099Y530282D03*
X795922Y531500D03*
X747200Y611900D03*
X826925Y57425D03*
X802786Y57150D03*
X841300Y54200D03*
X818785Y50692D03*
X803000Y117100D03*
X813349Y73142D03*
X809349Y73197D03*
X821962Y189277D03*
X801385Y183067D03*
X801340Y179597D03*
X831504Y199129D03*
X843419Y261781D03*
X840591Y264609D03*
X837619Y255281D03*
X834791Y258109D03*
X831609Y261291D03*
X828781Y264119D03*
X836955Y245662D03*
X834127Y248490D03*
X830945Y251672D03*
X828117Y254500D03*
X832148Y204444D03*
X816079Y250464D03*
X802227Y208424D03*
X802246Y205826D03*
X807468Y234464D03*
X808923Y245979D03*
X806968Y253464D03*
X804600Y210800D03*
X808400D03*
X816900Y231700D03*
X803160Y259454D03*
X803150Y256336D03*
X807177Y261023D03*
X814262Y218950D03*
X810277Y243190D03*
X810688Y238944D03*
X803129Y240535D03*
X803158Y237414D03*
X806862Y243302D03*
X806918Y237804D03*
X826000Y233400D03*
X828000Y243100D03*
X854419Y307581D03*
X851591Y310409D03*
X848409Y313591D03*
X845581Y316419D03*
X858919Y292081D03*
X856091Y294909D03*
X852909Y298091D03*
X850081Y300919D03*
X852919Y286081D03*
X850091Y288909D03*
X846909Y292091D03*
X844081Y294919D03*
X849419Y267581D03*
X846591Y270409D03*
X843409Y273591D03*
X840581Y276419D03*
X847419Y280581D03*
X844591Y283409D03*
X841409Y286591D03*
X838581Y289419D03*
X837409Y267791D03*
X834581Y270619D03*
X807666Y331334D03*
X822817Y331022D03*
X825646Y328193D03*
X803300Y303700D03*
X810300Y326450D03*
X823250Y319350D03*
X814450Y306950D03*
X810079Y271264D03*
X809968Y290464D03*
X808400Y300900D03*
X812164Y279674D03*
X811600Y317300D03*
X802363Y336637D03*
X804837Y334163D03*
X817514Y336325D03*
X820343Y333496D03*
X810946Y389734D03*
X811112Y393735D03*
X857581Y391433D03*
X817700Y385700D03*
X851100Y407500D03*
X861000Y410500D03*
X806400Y398700D03*
X810100Y404934D03*
X857000Y410600D03*
X850950Y489300D03*
X846000Y476100D03*
X849050Y481050D03*
X809384Y484984D03*
X800800Y526900D03*
X804584Y526584D03*
X829500Y481500D03*
X821050Y533350D03*
X813150Y533450D03*
X888551Y226649D03*
X882871Y243771D03*
X892449Y241249D03*
X886300Y221150D03*
X896969Y301500D03*
X883240Y301973D03*
X888668Y322100D03*
X886540Y388996D03*
X872750Y403400D03*
G54D151*
G01X722835Y292519D02*
X724416Y294100D01*
X727553D01*
X729134Y292519D01*
G01X768561Y210008D02*
Y212261D01*
X770079Y213779D01*
G01X764900Y207200D02*
Y208060D01*
X765298Y208458D01*
Y212148D01*
X766929Y213779D01*
G01X744882Y220079D02*
X746497Y218464D01*
X749566D01*
X751181Y220079D01*
G01X755898Y287804D02*
X753596D01*
X752698Y288702D01*
Y291002D01*
X751181Y292519D01*
G54D13*
X38780Y51460D03*
X76100Y693700D03*
X89034Y59335D03*
X110220Y485398D03*
X142100Y523300D03*
X105920Y493118D03*
X110220Y493078D03*
X108600Y573950D03*
X123900Y651400D03*
X127900D03*
X140700Y653500D03*
X111200Y713300D03*
X80600Y688900D03*
X203500Y520300D03*
X199500Y520400D03*
X184167Y506384D03*
X183277Y489078D03*
X178920D03*
X151900Y637300D03*
X147800D03*
X168900Y637000D03*
X149400Y626200D03*
X193285Y624500D03*
X189185D03*
X185085D03*
X181085D03*
X177000Y623400D03*
X172900D03*
X164800Y637000D03*
X197555Y636657D03*
X200850Y646400D03*
X145300Y626200D03*
X208516Y656901D03*
X196648Y657021D03*
X161000Y647700D03*
X144800Y653500D03*
X164349Y698815D03*
X151749Y699115D03*
X166400Y708200D03*
X154300Y706915D03*
X216900Y515666D03*
X212600Y520400D03*
X225600Y518780D03*
X269600Y531500D03*
X252272Y616581D03*
X225900Y627100D03*
X229900Y628400D03*
X221900Y627100D03*
X238000Y626200D03*
X234000D03*
X223400Y641400D03*
X244156Y617187D03*
X242900Y679100D03*
X258431Y707890D03*
X249842Y710710D03*
X339851Y182917D03*
X340942Y531926D03*
X314181Y589450D03*
X297175Y538454D03*
X305100Y661500D03*
X289800Y663900D03*
X328000Y673300D03*
X291700Y733600D03*
X287620Y733620D03*
X370682Y196274D03*
X350000Y524400D03*
X354440Y489230D03*
X356680Y589064D03*
X374292Y586800D03*
X350000Y532400D03*
X385600Y535900D03*
X345900Y581500D03*
X392133Y597890D03*
X468200Y66000D03*
X463200Y59100D03*
X444754Y45801D03*
X472500Y65900D03*
X639067Y361991D03*
X613223Y375927D03*
X646469Y420886D03*
X637147Y400197D03*
X632628Y558027D03*
X727150Y191250D03*
X722150D03*
X725678Y180392D03*
X711150Y181000D03*
X716650Y191250D03*
X705650D03*
X711150D03*
X714090Y328240D03*
X706000Y328200D03*
X727200Y359500D03*
X722500Y349700D03*
X713500Y359600D03*
X718000Y349700D03*
X689000Y503200D03*
X713575Y556177D03*
X728000Y583650D03*
X703800Y604900D03*
X784161Y126815D03*
X784400Y102700D03*
X741300Y192200D03*
X758100Y191800D03*
X754000Y192200D03*
X738365Y359435D03*
X790400Y419800D03*
X795922Y526308D03*
X777200Y500200D03*
X759200Y504200D03*
X753099Y526466D03*
X748899Y526366D03*
X818688Y406655D03*
X857000Y406800D03*
X805249Y523277D03*
X885568Y322041D03*
G54D31*
X61284Y643900D03*
X143049Y740015D03*
X145100Y691600D03*
X200686Y698355D03*
X272000Y715100D03*
X294800Y524750D03*
X299319Y553653D03*
X290700Y543000D03*
X302070Y612350D03*
X281860Y644250D03*
X291204Y688120D03*
X377200Y543200D03*
X358986Y639880D03*
X350230Y702620D03*
X442535Y34357D03*
X626722Y368128D03*
X610110Y521543D03*
X616700Y467000D03*
X621860Y554943D03*
X639300Y557500D03*
X741030Y452700D03*
X814434Y389702D03*
X805900Y477200D03*
G54D22*
X75000Y140000D03*
Y171500D03*
X800500Y588800D03*
G54D142*
X893634Y364633D03*
Y397685D03*
G54D106*
X543658Y32085D03*
G54D124*
X633266Y540996D03*
Y535090D03*
X621054D03*
Y540996D03*
G54D115*
X638780Y69685D03*
X629921D03*
X621063D03*
X641732Y117323D03*
X638780Y114567D03*
X635827Y120079D03*
X632873Y117323D03*
X629921Y114567D03*
X626969Y120079D03*
X624015Y117323D03*
X621063Y114567D03*
X618110Y120079D03*
X641732Y102362D03*
X638780Y99606D03*
X635827Y105118D03*
X632873Y102362D03*
X629921Y99606D03*
X621063D03*
X624015Y102362D03*
X626969Y105118D03*
X618110D03*
X641732Y87402D03*
X638780Y84646D03*
X635827Y90157D03*
X632873Y87402D03*
X626969Y90157D03*
X629921Y84646D03*
X624015Y87402D03*
X621063Y84646D03*
X618110Y90157D03*
X641732Y72441D03*
X635827Y75197D03*
X632873Y72441D03*
X626969Y75197D03*
X624015Y72441D03*
X618110Y75197D03*
X717520Y69685D03*
X708661D03*
X699803D03*
X720472Y117323D03*
X717520Y114567D03*
X714567Y120079D03*
X711613Y117323D03*
X708661Y114567D03*
X705709Y120079D03*
X702755Y117323D03*
X699803Y114567D03*
X696850Y120079D03*
X720472Y102362D03*
X717520Y99606D03*
X714567Y105118D03*
X711613Y102362D03*
X708661Y99606D03*
X699803D03*
X702755Y102362D03*
X705709Y105118D03*
X696850D03*
X720472Y87402D03*
X717520Y84646D03*
X714567Y90157D03*
X711613Y87402D03*
X705709Y90157D03*
X708661Y84646D03*
X702755Y87402D03*
X699803Y84646D03*
X696850Y90157D03*
X720472Y72441D03*
X714567Y75197D03*
X711613Y72441D03*
X705709Y75197D03*
X702755Y72441D03*
X696850Y75197D03*
G54D40*
X65900Y671000D03*
X65700Y660900D03*
X70600Y665800D03*
X60700Y665900D03*
X70800Y660700D03*
X60800Y660900D03*
X70700Y671000D03*
X60600Y670900D03*
X65714Y665850D03*
X135019Y706095D03*
X130019D03*
X139916Y705822D03*
X130019Y724095D03*
X135019Y714845D03*
Y719095D03*
Y723595D03*
Y710595D03*
X130019Y720495D03*
Y716895D03*
Y713295D03*
Y709695D03*
X139916Y723822D03*
Y720222D03*
Y716622D03*
Y713022D03*
Y709422D03*
X306486Y643750D03*
X306286Y633650D03*
X311186Y638550D03*
X301286Y638650D03*
X311386Y633450D03*
X301386Y633650D03*
X311286Y643750D03*
X301186Y643650D03*
X306300Y638600D03*
X295634Y710070D03*
X290520Y715120D03*
X300620Y715220D03*
X290720Y705120D03*
X300720Y704920D03*
X290620Y710120D03*
X300520Y710020D03*
X295620Y705120D03*
X295820Y715220D03*
X371400Y606400D03*
X358900Y612800D03*
X358800Y606300D03*
X365300Y606500D03*
X371400Y612700D03*
X371300Y618800D03*
X365500Y619000D03*
X358900Y618800D03*
X365164Y612620D03*
X468000Y35400D03*
X464000Y35500D03*
X468000Y39500D03*
Y31500D03*
X472000Y35500D03*
X601500Y363600D03*
X629200Y536040D03*
X629080Y539920D03*
X625500Y536100D03*
X625300Y539900D03*
X700546Y577599D03*
X691796D03*
X691296Y572599D03*
X705696D03*
X696296Y577599D03*
X709296Y572599D03*
Y577599D03*
X702096Y572599D03*
X694896D03*
X698496D03*
X704796Y577599D03*
X709569Y582496D03*
X698769D03*
X695169D03*
X691569D03*
X702369D03*
X705969D03*
X810200Y494900D03*
X815100Y499800D03*
X805200Y499900D03*
X815300Y494700D03*
X805300Y494900D03*
X815200Y505000D03*
X805100Y504900D03*
X810214Y499850D03*
X810400Y505000D03*
G54D133*
X668500Y710050D03*
Y709550D03*
G54D152*
G01X164039Y460299D02*
X167870D01*
X170243Y457926D01*
X177653D01*
X179494Y459767D01*
G01X212150Y495300D02*
X220521D01*
G01X716535Y301968D02*
X714619Y303884D01*
G01X788976Y245275D02*
X787402Y243701D01*
G54D143*
G01X66278Y572290D02*
X67853Y573865D01*
G01X66278Y556542D02*
X67853Y558117D01*
G01X69427Y584888D02*
X67852Y586463D01*
G01X69427Y575439D02*
X69428D01*
X71002Y577013D01*
G01X66278Y569140D02*
X66277D01*
X64701Y570716D01*
G01X66278Y562841D02*
X66276D01*
X64701Y564416D01*
G01X66278Y537644D02*
X66273D01*
X64400Y539000D01*
G01X66278Y540794D02*
X66273D01*
X64701Y542366D01*
G01X69427Y569140D02*
Y569141D01*
X67853Y570715D01*
G01X72577Y581738D02*
X74151Y583312D01*
X74152D01*
G01X66278Y584888D02*
X64703Y586463D01*
G01X66278Y553392D02*
X65105D01*
X63456Y555041D01*
G01X66278Y565990D02*
X66277D01*
X64701Y567566D01*
G01X66278Y559691D02*
X66276D01*
X64701Y561266D01*
G01X88325Y575439D02*
X86750Y573864D01*
G01X88325Y572290D02*
X89899Y573864D01*
G01X88325Y565990D02*
X86750Y567565D01*
G01X91474Y547093D02*
X94473D01*
G01X91474Y562841D02*
X91473D01*
X89899Y564415D01*
G01X91474Y550242D02*
X103400D01*
X106272Y547370D01*
G01X88325Y584888D02*
Y584890D01*
X89901Y586466D01*
Y587466D01*
G01X91474Y572290D02*
Y572293D01*
X89901Y573866D01*
X89899Y573864D01*
G01X91474Y584888D02*
X91498D01*
X93051Y586441D01*
Y587466D01*
G01X85175Y565990D02*
X83600Y567565D01*
G01X91474Y575439D02*
X93049Y573864D01*
G01X91474Y565990D02*
X89899Y567565D01*
G01X88325Y569140D02*
Y569139D01*
X89899Y567565D01*
G01X91474Y581738D02*
X93048Y580164D01*
G01X88325Y559691D02*
X88324D01*
X86750Y561265D01*
G01X91474Y553392D02*
X94720Y556638D01*
Y557158D01*
G01X91474Y537644D02*
Y536749D01*
X92600Y535623D01*
G01X91474Y540794D02*
X96371Y535897D01*
Y534124D01*
G01X157874Y585039D02*
X156299Y586614D01*
G01X186220Y553543D02*
Y553546D01*
X184646Y555120D01*
G01X164173Y553543D02*
X164172D01*
X162597Y555118D01*
G01X161023Y553543D02*
Y553544D01*
X162597Y555118D01*
G01X173622Y575590D02*
X175298Y577266D01*
G01X243020Y552558D02*
Y551989D01*
X245743Y549266D01*
Y546963D01*
G01X322277Y548693D02*
X321503D01*
X319135Y546325D01*
X315252D01*
G01X327250Y592060D02*
X334190D01*
X334250Y592000D01*
G01X309116Y554949D02*
X310914Y556747D01*
X313821D01*
G01X374844Y84695D02*
Y87900D01*
G01X344958Y110328D02*
X341484D01*
G01X374844Y80095D02*
Y76700D01*
G01X616900Y343000D02*
X617027Y343127D01*
Y349816D01*
G01X633800Y341450D02*
X632008Y343242D01*
X630108D01*
G01X615150Y364200D02*
Y364230D01*
X615057Y364137D01*
Y359016D01*
G01X617023Y372415D02*
X616774Y372166D01*
Y371007D01*
X616703Y370936D01*
Y365753D01*
X615150Y364200D01*
G01X633216Y539027D02*
X636127D01*
X637600Y540500D01*
X639500D01*
G01X729134Y223228D02*
X729135D01*
X730709Y221654D01*
G01X733858D02*
X735432Y223228D01*
X735433D01*
G01X732283Y220079D02*
X733858Y221654D01*
G01X730709D02*
X732283Y220080D01*
Y220079D01*
G01X722835Y223228D02*
X722836D01*
X724410Y221654D01*
G01D02*
X725984Y220080D01*
Y220079D01*
G01X724410Y234252D02*
X725984Y232678D01*
Y232677D01*
G01X724410Y240551D02*
X725984Y238977D01*
Y238976D01*
G01X722835Y248425D02*
Y248255D01*
X724240Y246850D01*
X724410D01*
G01X722835Y254724D02*
X722836D01*
X724410Y253150D01*
G01D02*
X725984Y251576D01*
Y251575D01*
G01X722835Y229527D02*
X722836D01*
X724410Y227953D01*
G01D02*
X725984Y226379D01*
Y226378D01*
G01Y292519D02*
X724409Y290944D01*
G01X732283Y292519D02*
X730708Y290944D01*
G01X724409D02*
X722835Y289370D01*
G01X730708Y290944D02*
X729134Y289370D01*
G01X735433Y273622D02*
X733859Y272048D01*
G01X732283Y289370D02*
X733857Y290944D01*
G01D02*
X735432Y292519D01*
X735433D01*
G01X727558Y290944D02*
X729133Y292519D01*
X729134D01*
G01X725984Y289370D02*
X727558Y290944D01*
G01X798425Y257874D02*
X798407D01*
X796822Y256289D01*
G01D02*
Y256043D01*
X798141Y254724D01*
X798425D01*
G01X784258Y262618D02*
X785813Y264173D01*
X785827D01*
G01X781080Y265763D02*
X779527Y264210D01*
Y264173D01*
G01X777967Y262576D02*
X777931D01*
X776378Y261023D01*
G01X779527Y257874D02*
X777953Y256300D01*
G01X770079Y248425D02*
X770115D01*
X771653Y246887D01*
G01X762205Y221654D02*
X760631Y223228D01*
X760630D01*
G01X782677Y220079D02*
X784252Y221654D01*
G01D02*
X785826Y223228D01*
X785827D01*
G01X779527D02*
X777953Y221654D01*
G01D02*
X776378Y220079D01*
G01X754331Y223228D02*
X754332D01*
X755906Y221654D01*
G01D02*
X757480Y220080D01*
Y220079D01*
G01X748031Y223228D02*
X746457Y221654D01*
G01D02*
X744882Y220079D01*
G01X792126Y235827D02*
X792128D01*
X793701Y234254D01*
G01X779527Y245275D02*
X779539D01*
X781127Y246863D01*
G01X792126Y229527D02*
X792128D01*
X793701Y227954D01*
G01X792126Y242126D02*
Y242106D01*
X793672Y240560D01*
G01X793701Y227954D02*
X795275Y226380D01*
Y226378D01*
G01X793672Y240560D02*
X795256Y238976D01*
X795275D01*
G01X760630Y298819D02*
X757480Y295669D01*
G01X751181Y298819D02*
X754331Y295669D01*
G01X741732Y289370D02*
X743306Y290944D01*
G01X735433Y289370D02*
X737007Y290944D01*
G01X795275Y298819D02*
X793701Y300393D01*
G01X798425Y283071D02*
X799999Y284645D01*
G01X801575Y301968D02*
X798425D01*
G01Y289370D02*
X799999Y290944D01*
G01X798425Y276771D02*
X799999Y278345D01*
G01X748031Y289370D02*
X749605Y290944D01*
G01X787402Y297243D02*
X788976Y295669D01*
G01X771654Y297243D02*
X773228Y295669D01*
G01X779527Y298819D02*
X781102Y297244D01*
G01X782677Y295669D02*
X781102Y297244D01*
G01X773228Y286220D02*
X774802Y287794D01*
G01X766929Y286220D02*
X768503Y287794D01*
G01X751181Y289370D02*
X751179D01*
X749605Y290944D01*
G01X744882Y292519D02*
X744881D01*
X743306Y290944D01*
G01X738583Y292519D02*
X738582D01*
X737007Y290944D01*
G01X759058Y300414D02*
Y300374D01*
X760613Y298819D01*
X760630D01*
G01X773228Y295669D02*
X773587D01*
X774006Y296088D01*
X775664D01*
X776083Y295669D01*
X776378D01*
G01D02*
X776736D01*
X777160Y296093D01*
X778818D01*
X779242Y295669D01*
X779527D01*
G01X798425Y273622D02*
Y273607D01*
X799974Y272058D01*
G01D02*
X799968Y272052D01*
Y272015D01*
X798425Y270472D01*
G01X799999Y278345D02*
X798425Y279919D01*
Y279921D01*
G01Y292519D02*
Y292518D01*
X799999Y290944D01*
G01X770079Y298819D02*
Y298818D01*
X771654Y297243D01*
G01D02*
X770080Y295669D01*
X770079D01*
G01X781102Y297244D02*
X779527Y295669D01*
G01X788976Y298819D02*
Y298817D01*
X787402Y297243D01*
G01D02*
X785828Y295669D01*
X785827D01*
G01X751181Y298819D02*
X749616Y297254D01*
X749579D01*
G01X793701Y300393D02*
X792127Y298819D01*
X792126D01*
G01X799999Y284645D02*
X798425Y286219D01*
Y286220D01*
G01X749579Y297254D02*
X751156Y295677D01*
X751173D01*
X751181Y295669D01*
G01X790526Y300406D02*
X788976Y301956D01*
Y301968D01*
G01X765369Y281474D02*
X766929Y283034D01*
Y283071D01*
G01X773228D02*
Y283033D01*
X771669Y281474D01*
G01D02*
X773222Y279921D01*
X773228D01*
G01X759070Y281514D02*
X760627Y283071D01*
X760630D01*
G01X749816Y303716D02*
Y303333D01*
X751181Y301968D01*
G01X777790Y304778D02*
X779527Y303041D01*
Y301968D01*
G01X769768Y304464D02*
X770079Y304153D01*
Y301968D01*
G01X759208Y304284D02*
X760630Y302862D01*
Y301968D01*
G01X781088Y294094D02*
X779527Y292533D01*
Y292519D01*
G01X782677Y286220D02*
X784251Y287794D01*
G01X776378Y286220D02*
X777952Y287794D01*
G01X770079Y286220D02*
X771653Y287794D01*
G01X763779Y286220D02*
X765353Y287794D01*
G01X762225Y297227D02*
X760667Y295669D01*
X760630D01*
G01X770079Y292519D02*
X771653Y294093D01*
G01X744882Y289370D02*
X746456Y290944D01*
G01D02*
X748031Y292519D01*
G01X738583Y289370D02*
X740157Y290944D01*
G01D02*
X741732Y292519D01*
G01X752230Y479374D02*
X754610D01*
X755800Y478184D01*
G01X806968Y253464D02*
X805708Y254724D01*
X804724D01*
G01X801575D02*
X801933D01*
X802321Y254336D01*
X803979D01*
X804367Y254724D01*
X804724D01*
G01X808923Y245979D02*
X806477Y248425D01*
X804724D01*
G01Y261023D02*
X807177D01*
G01X801575Y279921D02*
X799999Y278345D01*
G01X801575Y298819D02*
Y301968D01*
G01X799974Y272058D02*
X801560Y270472D01*
X801575D01*
G01X808400Y300900D02*
X807900D01*
X805819Y298819D01*
X804724D01*
G01X810079Y271264D02*
X809287Y270472D01*
X804724D01*
G54D107*
X490835Y42057D03*
G54D23*
X70865Y98425D03*
Y472440D03*
X49213Y740157D03*
X314960Y472440D03*
X405511Y39370D03*
X364173Y740157D03*
X612204Y433070D03*
Y740157D03*
X875985Y59055D03*
X875984Y433070D03*
Y740157D03*
G54D32*
X77766Y637546D03*
Y629946D03*
X83750Y654654D03*
X91550Y654554D03*
X83750Y662254D03*
X91550Y662154D03*
X101749Y730715D03*
Y738315D03*
X94020Y730691D03*
Y738291D03*
X124820Y732391D03*
Y739991D03*
X109449Y730715D03*
Y738315D03*
X117149Y730715D03*
Y738315D03*
X132651Y732415D03*
Y740015D03*
X219600Y717700D03*
Y710100D03*
X211800Y717700D03*
Y710100D03*
X324636Y627604D03*
Y635204D03*
X332436Y627504D03*
Y635104D03*
X319536Y658504D03*
X311636D03*
X311936Y609096D03*
Y601496D03*
X321470Y698774D03*
Y706374D03*
X313670Y698874D03*
Y706474D03*
X319536Y666104D03*
X311636D03*
X309300Y683100D03*
Y675500D03*
X298470Y731174D03*
Y738774D03*
X306370Y731174D03*
Y738774D03*
X659600Y523200D03*
X651500D03*
X659600Y530800D03*
X651500D03*
X692000Y529500D03*
Y537100D03*
X742700Y457680D03*
Y465280D03*
X821050Y519654D03*
Y527254D03*
X813150Y519654D03*
Y527254D03*
X828250Y488954D03*
Y496554D03*
X836050Y488854D03*
Y496454D03*
G54D134*
X761800Y438310D03*
Y461858D03*
G54D41*
X125481Y460299D03*
Y465299D03*
Y470299D03*
Y475299D03*
Y480299D03*
Y485299D03*
Y490299D03*
Y495299D03*
X164039Y460299D03*
Y495299D03*
Y490299D03*
Y485299D03*
Y480299D03*
Y475299D03*
Y470299D03*
Y465299D03*
X220521Y460300D03*
X259079D03*
X220521Y465300D03*
Y470300D03*
Y475300D03*
Y480300D03*
Y485300D03*
Y490300D03*
Y495300D03*
X259079D03*
Y490300D03*
Y485300D03*
Y480300D03*
Y475300D03*
Y470300D03*
Y465300D03*
G54D125*
X633216Y539027D03*
Y537059D03*
X621104D03*
Y539027D03*
G54D14*
X58010Y52510D03*
X75373Y509879D03*
X75405Y517477D03*
X69900Y510000D03*
X69778Y517477D03*
X46100Y674984D03*
X79570Y58460D03*
X81032Y517477D03*
X81068Y509866D03*
X105920Y485398D03*
X86659Y517477D03*
X86673Y510000D03*
X92000Y517400D03*
X101100Y515300D03*
X101113Y522777D03*
X142000Y515500D03*
X93531Y496341D03*
X132100Y651400D03*
X136100D03*
X113349Y697047D03*
X117449D03*
X121549Y694747D03*
X193000Y506400D03*
X146112Y516498D03*
X183320Y481498D03*
X178920D03*
X174715Y520420D03*
X187000Y520400D03*
X191100Y519900D03*
X170700Y520400D03*
X166600D03*
X178869Y520393D03*
X182874Y520391D03*
X160727Y520222D03*
X150112Y516498D03*
X156721Y520192D03*
X188400Y506300D03*
X185276Y636268D03*
X177100Y637000D03*
X173000D03*
X202560Y627466D03*
X197315Y625797D03*
X153700Y626200D03*
X189376Y636268D03*
X193476D03*
X181146Y637008D03*
X188400Y647400D03*
X149300Y648400D03*
X204357Y656886D03*
X191746Y657042D03*
X165000Y647700D03*
X155849Y699115D03*
X158349Y706915D03*
X230262Y518680D03*
X234348Y518614D03*
X238648D03*
X242700Y518620D03*
X243400Y642900D03*
X248215Y616587D03*
X219200Y644000D03*
X231300Y645500D03*
X211706Y641392D03*
X251900Y679700D03*
X238936Y666869D03*
X258500Y679200D03*
X266800Y671000D03*
X262645Y707901D03*
X270900Y674000D03*
X293150Y538700D03*
X289050D03*
X300200Y593600D03*
X304300D03*
X336500Y673500D03*
X391262Y72271D03*
X386027Y72240D03*
X362484Y200119D03*
X349004Y183030D03*
X363553Y479662D03*
X382550Y584806D03*
X360820Y590236D03*
X352480Y589564D03*
X378350Y584806D03*
X345287Y540959D03*
X391549Y563600D03*
X387733Y597990D03*
X348600Y639000D03*
X444722Y53415D03*
X603164Y544203D03*
X639040Y161110D03*
X634661Y370756D03*
X620822Y375864D03*
X623239Y340879D03*
X608500Y339400D03*
X640160Y525243D03*
X619400Y567200D03*
X623542Y567152D03*
X732000Y192400D03*
X734028Y182346D03*
X716650Y181000D03*
X710060Y328260D03*
X727000Y349700D03*
X731400Y359400D03*
X711700Y348700D03*
X696527Y460706D03*
X696700Y473300D03*
X702390Y492260D03*
X731676Y591129D03*
X707826Y604879D03*
X716345Y611790D03*
X777700Y77600D03*
X795600Y191800D03*
X790600D03*
X762200Y192200D03*
X745700Y192400D03*
X737000D03*
X775500Y191700D03*
X749900Y192100D03*
X785600Y191800D03*
X738465Y349635D03*
X777000Y492500D03*
X751400Y504200D03*
X777084Y526450D03*
X841300Y61280D03*
X809349Y70036D03*
X813449D03*
X805600Y191800D03*
X800600D03*
X810600D03*
X857569Y388333D03*
X861000Y406800D03*
X882913Y232198D03*
G54D116*
X651575Y20039D03*
X608267D03*
X641732Y126811D03*
X624015D03*
X651575Y72441D03*
X608267D03*
X730315Y20039D03*
X687007D03*
X720472Y126811D03*
X702755D03*
X730315Y72441D03*
X687007D03*
G54D50*
G01X274245Y549394D02*
X270021D01*
G01X261248Y700086D02*
X260931Y699769D01*
Y692574D01*
G01X254800Y689400D02*
Y687274D01*
X253800Y686274D01*
X251091D01*
G01X269200Y699600D02*
X271240Y697560D01*
Y692850D01*
G01X263000Y679250D02*
X263491Y679741D01*
Y686074D01*
G01X258371Y692574D02*
Y696329D01*
X256900Y697800D01*
Y699715D01*
G01D02*
Y702909D01*
X258431Y704440D01*
G01X279400Y686400D02*
X279350Y686350D01*
X276360D01*
G01X375200Y63400D02*
X374050Y62250D01*
X372000D01*
G01Y72150D02*
X375300D01*
G01X576160Y62835D02*
X578285D01*
X580000Y64550D01*
G01X571040Y54765D02*
Y52620D01*
X568430Y50010D01*
G01X557660Y53630D02*
Y49540D01*
X559600Y47600D01*
G01X707944Y464430D02*
Y457556D01*
X708000Y457500D01*
G01X765260Y58080D02*
Y56736D01*
X768336Y53660D01*
X769812D01*
G01X760140Y50010D02*
X756431Y54010D01*
G01X773200Y97600D02*
X771300Y95700D01*
X768700D01*
X767860Y96540D01*
Y99750D01*
G01X761900Y81700D02*
X762700Y82500D01*
X766000D01*
X766940Y81560D01*
Y78750D01*
G01X815076Y50692D02*
X818785D01*
X154724Y537795D03*
Y540945D03*
Y544094D03*
X157874Y537795D03*
Y540945D03*
Y544094D03*
X161023Y537795D03*
Y540945D03*
Y544094D03*
X154724Y597638D03*
Y600787D03*
Y603937D03*
X157874Y597638D03*
Y600787D03*
Y603937D03*
X161023Y597638D03*
Y600787D03*
Y603937D03*
X214567Y537795D03*
Y540945D03*
Y544094D03*
X217716Y537795D03*
Y540945D03*
Y544094D03*
X220866Y537795D03*
Y540945D03*
Y544094D03*
X214567Y597638D03*
Y600787D03*
Y603937D03*
X217716Y597638D03*
Y600787D03*
Y603937D03*
X220866Y597638D03*
Y600787D03*
Y603937D03*
X713386Y216929D03*
X716535D03*
X719685D03*
X713386Y213779D03*
X716535D03*
X719685D03*
X716535Y210630D03*
X719685D03*
X716535Y301968D03*
X719685D03*
X713386Y298819D03*
X716535D03*
X719685D03*
X713386Y295669D03*
X716535D03*
X719685D03*
X798425Y216929D03*
Y213779D03*
Y210630D03*
Y301968D03*
Y298819D03*
Y295669D03*
X801575Y216929D03*
X804724D03*
X801575Y213779D03*
X804724D03*
X801575Y210630D03*
Y301968D03*
Y298819D03*
X804724D03*
X801575Y295669D03*
X804724D03*
G54D153*
G01X72577Y569140D02*
X74152Y567565D01*
G01X72577Y565990D02*
X71002Y567565D01*
G01X88325Y556542D02*
Y556540D01*
X86750Y554965D01*
G01X154724Y569291D02*
G03X153400Y570125I-1324J-634D01*
G01X149416D01*
G02X144749Y572057I-1J6600D01*
G01X144589Y572217D01*
G03X142186Y573213I-2404J-2403D01*
G01X136575D01*
G02X131908Y575145I-1J6600D01*
G01X131026Y576027D01*
G03X128623Y577023I-2404J-2403D01*
G01X116737D01*
G03X114836Y575122I0J-1901D01*
G03X116738Y573220I1902J0D01*
G01X126947D01*
G02X128428Y572605I0J-2091D01*
G01X128451Y572582D01*
G02X129090Y571042I-1539J-1541D01*
G01Y570969D01*
G03X130607Y569636I1344J0D01*
G01X85175Y556542D02*
X85177D01*
X86750Y558115D01*
G01X154724Y572441D02*
G02X153400Y571725I-1324J866D01*
G01X149416D01*
G02X145881Y573189I0J5000D01*
G01X145721Y573349D01*
G03X142186Y574813I-3535J-3536D01*
G01X136575D01*
G02X133040Y576277I0J5000D01*
G01X132158Y577159D01*
G03X128623Y578623I-3535J-3536D01*
G01X116737D01*
G03X113236Y575122I0J-3501D01*
G03X116738Y571620I3502J0D01*
G01X126947D01*
G02X127294Y571475I-1J-490D01*
G01X127319Y571450D01*
X127320D01*
G02X127490Y571041I-408J-410D01*
G01Y570699D01*
G02X126347Y569556I-1143J0D01*
G01X86750Y586463D02*
X85175Y584888D01*
G01X86750Y583313D02*
X85175Y581738D01*
G01X154724Y575590D02*
G03X153631Y576530I-1093J-165D01*
G01X149963D01*
G03X148409Y575672I0J-1836D01*
G01X144876Y590854D02*
X145540Y590191D01*
G03X146724Y589700I1185J1184D01*
G01X147750D01*
G02X150396Y588604I0J-3742D01*
G01X151182Y587818D01*
G03X152399Y587314I1217J1217D01*
G01X153368D01*
G03X154189Y587654I0J1161D01*
G01X154724Y588189D01*
G01X148409Y579353D02*
G03X149864Y578130I1455J254D01*
G01X153632D01*
G03X153756Y578136I0J1282D01*
G03X154724Y578740I-124J1276D01*
G01X144876Y587173D02*
X145152Y587449D01*
G02X146724Y588100I1572J-1572D01*
G01X147750D01*
G02X149264Y587472I-1J-2142D01*
G01X150050Y586686D01*
Y586687D01*
G03X152400Y585714I2349J2348D01*
G01X153368D01*
G02X154530Y585232I-1J-1644D01*
G01X154724Y585039D01*
G01X793674Y265758D02*
Y265721D01*
X792126Y264173D01*
G01X793699Y262634D02*
X793736D01*
X795275Y264173D01*
G01X792126Y295669D02*
X793700Y297243D01*
G01X796849D02*
X795275Y295669D01*
G01X790545Y290959D02*
X792105Y292519D01*
X792126D01*
G01X793694Y290959D02*
X795254Y292519D01*
X795275D01*
G01X793703Y287797D02*
X792126Y286220D01*
G01X795275D02*
X796839Y287784D01*
G01X793675Y284637D02*
Y284620D01*
X792126Y283071D01*
G01X793679Y281508D02*
X793712D01*
X795275Y283071D01*
G01X793675Y278357D02*
Y278320D01*
X792126Y276771D01*
G01X796868Y278364D02*
X795275Y276771D01*
G01X793737Y275196D02*
X793700D01*
X792126Y273622D01*
G01X793682Y272064D02*
X793717D01*
X795275Y273622D01*
G01X793683Y268879D02*
X793682D01*
X792126Y267323D01*
G01X796850Y268910D02*
Y268898D01*
X795275Y267323D01*
G01X820218Y266800D02*
X820368Y266950D01*
X830787D01*
X834337Y263400D01*
X837334D01*
X839067Y265133D01*
G02X840067I500J-500D01*
G01X840591Y264609D01*
G01X820218Y269000D02*
X820668Y268550D01*
X831450D01*
X835000Y265000D01*
X836671D01*
X837936Y266265D01*
G03Y267264I-500J499D01*
G01X837409Y267791D01*
G01X834791Y258109D02*
X834115Y258785D01*
G03X833415I-350J-350D01*
G01X831595Y256965D01*
X827772D01*
X824294Y260443D01*
X820461D01*
X820218Y260200D01*
G01X801575Y267323D02*
Y266925D01*
X802522Y265978D01*
X803806D01*
X804062Y265722D01*
X808986D01*
X814202Y260506D01*
X817712D01*
X818018Y260200D01*
G01X831609Y261291D02*
X832283Y260617D01*
G02Y259916I-350J-351D01*
G01X830932Y258565D01*
X828435D01*
X824957Y262043D01*
X820575D01*
X820218Y262400D01*
G01X818018D02*
X817724Y262106D01*
X814865D01*
X809649Y267322D01*
X804725D01*
X804724Y267323D01*
G01X834127Y248490D02*
X833451Y249166D01*
G03X832751I-350J-350D01*
G01X830931Y247346D01*
X828054D01*
X825004Y250396D01*
Y251704D01*
X822823Y253885D01*
X820503D01*
X820218Y253600D01*
G01X801575Y264173D02*
X803380Y262368D01*
X805282D01*
X805582Y262668D01*
X807859D01*
X809768Y260759D01*
Y257414D01*
X813275Y253907D01*
X817711D01*
X818018Y253600D01*
G01X820218Y255800D02*
X820533Y255485D01*
X823486D01*
X826604Y252368D01*
Y251059D01*
X828717Y248946D01*
X830268D01*
X831619Y250297D01*
G03Y250998I-351J351D01*
G01X830945Y251672D01*
G01X818018Y255800D02*
X817725Y255507D01*
X813938D01*
X811368Y258077D01*
Y261422D01*
X808522Y264268D01*
X804819D01*
X804724Y264173D01*
G01X851591Y310409D02*
X851115Y310885D01*
G03X850015I-550J-550D01*
G01X846665Y307535D01*
X846664D01*
X844529Y305400D01*
X832163D01*
X826718Y299955D01*
X820373D01*
X820218Y299800D01*
G01X801575Y295669D02*
X804200Y294069D01*
X806715D01*
X812721Y300075D01*
X817743D01*
X818018Y299800D01*
G01X848409Y313591D02*
X848883Y313117D01*
G02Y312017I-550J-550D01*
G01X843866Y307000D01*
X831500D01*
X826055Y301555D01*
X820663D01*
X820218Y302000D01*
G01X804724Y295669D02*
X806052D01*
X812058Y301675D01*
X817693D01*
X818018Y302000D01*
G01X856091Y294909D02*
X855567Y295433D01*
G03X854567I-500J-500D01*
G01X852934Y293800D01*
X849937D01*
X844437Y299300D01*
X834563D01*
X828663Y293400D01*
X820418D01*
X820218Y293200D01*
G01X801575Y292519D02*
X804300Y290812D01*
X807502D01*
X810065Y293375D01*
X817843D01*
X818018Y293200D01*
G01X820218Y295400D02*
X820618Y295000D01*
X828000D01*
X833900Y300900D01*
X845100D01*
X850600Y295400D01*
X852271D01*
X853435Y296564D01*
G03Y297565I-501J501D01*
G01X852909Y298091D01*
G01X818018Y295400D02*
X817593Y294975D01*
X809402D01*
X806839Y292412D01*
X804831D01*
X804724Y292519D01*
G01X850091Y288909D02*
X849567Y289433D01*
G03X848567I-500J-500D01*
G01X847226Y288092D01*
X844545D01*
X840037Y292600D01*
X835663D01*
X829967Y286904D01*
X820522D01*
X820218Y286600D01*
G01X801575Y286220D02*
Y285824D01*
X802779Y284620D01*
X809692D01*
X811994Y286922D01*
X817696D01*
X818018Y286600D01*
G01X846909Y292091D02*
X847436Y291564D01*
G02Y290565I-500J-499D01*
G01X846563Y289692D01*
X845208D01*
X840700Y294200D01*
X835000D01*
X829304Y288504D01*
X820514D01*
X820218Y288800D01*
G01X818018D02*
X817740Y288522D01*
X811331D01*
X809029Y286220D01*
X804724D01*
G01X844591Y283409D02*
X844067Y283933D01*
G03X843067I-500J-500D01*
G01X839441Y280307D01*
X820525D01*
X820218Y280000D01*
G01X801575Y283071D02*
Y282725D01*
X802830Y281470D01*
X806352D01*
X806676Y281794D01*
X813914D01*
X815534Y280174D01*
X817844D01*
X818018Y280000D01*
G01X841409Y286591D02*
X841935Y286065D01*
G02Y285064I-501J-501D01*
G01X838778Y281907D01*
X820511D01*
X820218Y282200D01*
G01X818018D02*
X817593Y281775D01*
X816196D01*
X814577Y283394D01*
X806013D01*
X805690Y283071D01*
X804724D01*
G01X820218Y273400D02*
X820418Y273600D01*
X836236D01*
X840244Y269592D01*
X843726D01*
X845067Y270933D01*
G02X846067I500J-500D01*
G01X846591Y270409D01*
G01X801575Y276771D02*
Y276525D01*
X802930Y275170D01*
X805386D01*
X805763Y275547D01*
X813161D01*
X814946Y273761D01*
X817657D01*
X818018Y273400D01*
G01X820218Y275600D02*
X820618Y275200D01*
X836899D01*
X840907Y271192D01*
X843063D01*
X843936Y272065D01*
G03Y273064I-500J500D01*
G01X843409Y273591D01*
G01X818018Y275600D02*
X817779Y275361D01*
X815610D01*
X813825Y277147D01*
X805100D01*
X804724Y276771D01*
G01X801575Y273622D02*
X804500Y272021D01*
X808509D01*
X809545Y273057D01*
X810851D01*
X813524Y270384D01*
Y268649D01*
X815073Y267100D01*
X817718D01*
X818018Y266800D01*
G01Y269000D02*
X817718Y268700D01*
X815736D01*
X815124Y269312D01*
Y271047D01*
X811514Y274657D01*
X808882D01*
X807846Y273621D01*
X804725D01*
X804724Y273622D01*
G54D144*
G01X172000Y577150D02*
X172033D01*
X173622Y578739D01*
Y578740D01*
G54D24*
X44206Y543876D03*
X36758Y543881D03*
X44187Y555153D03*
X36687D03*
X44000Y549500D03*
X36500D03*
X44206Y538249D03*
X36658Y538254D03*
X44106Y532622D03*
X64746Y647850D03*
X130400Y534600D03*
X140300Y529700D03*
X140424Y538335D03*
X130400Y530300D03*
X123403Y609818D03*
X126397Y601923D03*
X126100Y632300D03*
Y636400D03*
X200800Y502800D03*
X182920Y473998D03*
X156800Y648400D03*
X148549Y683715D03*
X158549Y711215D03*
X212100Y495300D03*
X271300Y474500D03*
X251466Y567108D03*
X251100Y573500D03*
X250850Y578300D03*
X243700Y588900D03*
X243010Y537139D03*
X251100Y585700D03*
X242970Y552558D03*
X264200Y539500D03*
X267600Y552100D03*
X243996Y560698D03*
Y564798D03*
X258274Y552061D03*
X251396Y556761D03*
X251477Y563068D03*
X228016Y658967D03*
X238200Y633200D03*
X243300Y601000D03*
X263273Y634343D03*
X275420Y718920D03*
X238900Y659100D03*
X261719Y662209D03*
X302432Y578108D03*
X277700Y575000D03*
X296800Y573700D03*
X297500Y569700D03*
X295100Y565600D03*
X302600Y564200D03*
X302876Y557611D03*
X316033Y535357D03*
X305448Y620477D03*
X285360Y647950D03*
Y652100D03*
X294782Y691947D03*
X345629Y193678D03*
X370372Y245284D03*
X343617Y231156D03*
X343659Y261112D03*
X370242Y224934D03*
X370472Y240684D03*
X345378Y517086D03*
X351261Y507831D03*
X358030Y481570D03*
X348700Y545100D03*
X389700Y568500D03*
X391181Y623786D03*
X391100Y610300D03*
X366064Y635920D03*
X490000Y49100D03*
X493200Y34000D03*
X485800Y67973D03*
X485925Y58850D03*
X596900Y373300D03*
X607708Y373437D03*
X633722Y375305D03*
X649800Y504100D03*
X642860Y549543D03*
X699920Y197740D03*
X688500Y255400D03*
X700000Y244800D03*
X685400Y249100D03*
X697300Y228400D03*
Y232400D03*
Y236850D03*
X684847Y240430D03*
X689000Y265100D03*
X688600Y259500D03*
X699403Y211743D03*
X699550Y203560D03*
X688947Y277530D03*
Y269230D03*
X688800Y285900D03*
X688947Y281730D03*
X686200Y307000D03*
X688947Y273430D03*
X674550Y470684D03*
X675900Y503900D03*
X699400Y504000D03*
X706538Y553602D03*
X722000Y569100D03*
X711200Y614500D03*
X719576Y594029D03*
X757720Y126510D03*
X785954Y514350D03*
X788684Y505600D03*
X780700Y518500D03*
X771019Y488799D03*
X747200Y508600D03*
X823200Y322500D03*
X809334Y480900D03*
X868950Y403400D03*
G54D135*
X749080Y477405D03*
Y473468D03*
X738564Y475437D03*
G54D42*
X126185Y460299D03*
Y495299D03*
Y490299D03*
Y485299D03*
Y480299D03*
Y475299D03*
Y470299D03*
Y465299D03*
X163335Y460299D03*
Y465299D03*
Y470299D03*
Y475299D03*
Y480299D03*
Y485299D03*
Y490299D03*
Y495299D03*
X258375Y460300D03*
X221225D03*
X258375Y465300D03*
Y470300D03*
Y475300D03*
Y480300D03*
Y485300D03*
Y490300D03*
Y495300D03*
X221225D03*
Y490300D03*
Y485300D03*
Y480300D03*
Y475300D03*
Y470300D03*
Y465300D03*
X267600Y582000D03*
Y587000D03*
Y592000D03*
Y597000D03*
X287600Y592000D03*
Y587000D03*
Y582000D03*
Y597000D03*
X379088Y526681D03*
Y521681D03*
X359088D03*
Y526681D03*
X379088Y536681D03*
Y531681D03*
X359088D03*
Y536681D03*
X648546Y449321D03*
Y454321D03*
Y459321D03*
X668546D03*
Y454321D03*
Y449321D03*
X648546Y464321D03*
X668546D03*
X830300Y388800D03*
Y393800D03*
X850300D03*
Y388800D03*
X830300Y398800D03*
Y403800D03*
X850300D03*
Y398800D03*
G54D60*
X178543Y728500D03*
X156657D03*
G54D126*
X630113Y531937D03*
X624207D03*
Y544149D03*
X630113D03*
G54D117*
X625894Y360600D03*
X628454D03*
X631014D03*
X633574D03*
Y347800D03*
X631014D03*
X628454D03*
X625894D03*
G54D33*
X70832Y656107D03*
X68273D03*
X65714D03*
X63155D03*
X60596D03*
Y675593D03*
X63155D03*
X65714D03*
X68273D03*
X70832D03*
X311418Y628857D03*
X308859D03*
X306300D03*
X303741D03*
X301182D03*
Y648343D03*
X303741D03*
X306300D03*
X308859D03*
X311418D03*
X300752Y700327D03*
X298193D03*
X295634D03*
X293075D03*
X290516D03*
Y719813D03*
X293075D03*
X295634D03*
X298193D03*
X300752D03*
X815332Y490107D03*
X812773D03*
X810214D03*
X807655D03*
X805096D03*
Y509593D03*
X807655D03*
X810214D03*
X812773D03*
X815332D03*
G54D15*
X58010Y49110D03*
X75373Y506479D03*
X75405Y514077D03*
X69900Y506600D03*
X69778Y514077D03*
X46100Y671584D03*
X79570Y55060D03*
X81032Y514077D03*
X81068Y506466D03*
X105920Y481998D03*
X86659Y514077D03*
X86673Y506600D03*
X92000Y514000D03*
X101100Y511900D03*
X101113Y519377D03*
X142000Y512100D03*
X93531Y492941D03*
X132100Y648000D03*
X136100D03*
X113349Y693647D03*
X117449D03*
X121549Y691347D03*
X193000Y503000D03*
X146112Y513098D03*
X183320Y478098D03*
X178920D03*
X174715Y517020D03*
X187000Y517000D03*
X191100Y516500D03*
X170700Y517000D03*
X166600D03*
X178869Y516993D03*
X182874Y516991D03*
X160727Y516822D03*
X150112Y513098D03*
X156721Y516792D03*
X188400Y502900D03*
X185276Y632868D03*
X177100Y633600D03*
X173000D03*
X202560Y624066D03*
X197315Y622397D03*
X153700Y622800D03*
X189376Y632868D03*
X193476D03*
X181146Y633608D03*
X188400Y644000D03*
X149300Y645000D03*
X204357Y653486D03*
X191746Y653642D03*
X165000Y644300D03*
X155849Y695715D03*
X158349Y703515D03*
X230262Y515280D03*
X234348Y515214D03*
X238648D03*
X242700Y515220D03*
X243400Y639500D03*
X248215Y613187D03*
X219200Y640600D03*
X231300Y642100D03*
X211706Y637992D03*
X251900Y676300D03*
X238936Y663469D03*
X258500Y675800D03*
X266800Y667600D03*
X262645Y704501D03*
X270900Y670600D03*
X300200Y590200D03*
X304300D03*
X293150Y535300D03*
X289050D03*
X336500Y670100D03*
X391262Y68871D03*
X386027Y68840D03*
X362484Y196719D03*
X349004Y179630D03*
X363553Y476262D03*
X382550Y581406D03*
X360820Y586836D03*
X352480Y586164D03*
X378350Y581406D03*
X345287Y537559D03*
X391549Y560200D03*
X387733Y594590D03*
X348600Y635600D03*
X444722Y50015D03*
X603164Y540803D03*
X639040Y157710D03*
X634661Y367356D03*
X620822Y372464D03*
X623239Y337479D03*
X608500Y336000D03*
X640160Y521843D03*
X619400Y563800D03*
X623542Y563752D03*
X732000Y189000D03*
X734028Y178946D03*
X716650Y177600D03*
X710060Y324860D03*
X727000Y346300D03*
X731400Y356000D03*
X711700Y345300D03*
X696527Y457306D03*
X696700Y469900D03*
X702390Y488860D03*
X731676Y587729D03*
X707826Y601479D03*
X716345Y608390D03*
X777700Y74200D03*
X795600Y188400D03*
X790600D03*
X762200Y188800D03*
X745700Y189000D03*
X737000D03*
X775500Y188300D03*
X749900Y188700D03*
X785600Y188400D03*
X738465Y346235D03*
X777000Y489100D03*
X751400Y500800D03*
X777084Y523050D03*
X809349Y66636D03*
X841300Y57880D03*
X813449Y66636D03*
X805600Y188400D03*
X800600D03*
X810600D03*
X857569Y384933D03*
X861000Y403400D03*
X882913Y228798D03*
G54D51*
X197243Y589764D03*
X203542Y592913D03*
X168898Y548819D03*
X172000Y577150D03*
X184645Y589764D03*
X175197D03*
X209842Y583464D03*
X187795Y570866D03*
X184646Y577165D03*
X187795D03*
X190945D03*
X190944Y574016D03*
X190945Y570866D03*
X187795Y574016D03*
X184646D03*
Y570866D03*
X187795Y564567D03*
X194094Y567716D03*
X190945D03*
X187795D03*
X184646D03*
X206692Y592913D03*
X184645Y539370D03*
X194094D03*
X203542Y545671D03*
X197243Y539371D03*
X206692Y555120D03*
X194093D03*
X184646D03*
X153149Y536221D03*
X165748Y558268D03*
X172048Y555120D03*
X156297Y558267D03*
X172048Y589764D03*
X168898D03*
Y561417D03*
Y570866D03*
X156299Y586614D03*
Y580315D03*
X159449Y567717D03*
X156299Y570866D03*
X197243Y592913D03*
X200393Y589764D03*
X187794Y586614D03*
X203542Y589764D03*
X187795Y592914D03*
X165748Y583464D03*
X209841Y574016D03*
X206692D03*
X165745Y564567D03*
X168895D03*
X159449Y561417D03*
X165748D03*
X172047D03*
X162598Y558268D03*
X168898D03*
X165748Y555118D03*
X159449D03*
X168898Y567717D03*
X159449Y570866D03*
X168898Y583464D03*
Y577165D03*
X159449Y586614D03*
X162598Y580315D03*
Y586614D03*
X165748D03*
X168898D03*
X159449Y577165D03*
X156299D03*
X168898Y580315D03*
X159449D03*
X162598Y577165D03*
X165748Y580315D03*
X162598Y583464D03*
X165748Y570866D03*
Y567717D03*
X162598D03*
X172047Y570866D03*
X162597Y555118D03*
X197243Y551970D03*
X194093D03*
X200395Y555120D03*
X181497Y551970D03*
Y589764D03*
X187795Y555120D03*
X206692Y564569D03*
Y561419D03*
Y558269D03*
Y567718D03*
X203543Y574017D03*
X206692Y583465D03*
X194093Y586614D03*
X178347Y551970D03*
X175197D03*
Y558268D03*
X178347Y589764D03*
X190945Y542519D03*
X172047Y545669D03*
Y551970D03*
X159449Y545671D03*
X162599Y545669D03*
X165749D03*
X184646Y548821D03*
Y545671D03*
X209842Y567717D03*
X184645Y542519D03*
X206692Y542521D03*
X209841Y577165D03*
X159449Y542521D03*
X156299Y545671D03*
X168898Y592913D03*
X181497Y545671D03*
X209842Y545669D03*
X165749Y548819D03*
X175197Y545671D03*
X162599Y542519D03*
X168898D03*
X156299Y542521D03*
X181496Y542520D03*
X159449Y548821D03*
X206692Y589763D03*
X172047Y548819D03*
X168898Y551969D03*
X162599Y548821D03*
X194093Y589764D03*
Y592913D03*
X162598Y561417D03*
X168898Y555119D03*
X181497Y548821D03*
X178346Y545670D03*
X206692Y586614D03*
X209842Y586613D03*
X209841Y592913D03*
X162595Y564567D03*
X162598Y570866D03*
X203542Y548821D03*
Y586614D03*
Y580315D03*
X178344Y577166D03*
X178346Y586615D03*
X181497Y586614D03*
X178347Y574018D03*
Y570868D03*
X190944Y586614D03*
X200394Y570866D03*
Y574016D03*
X203543Y561418D03*
Y564568D03*
X165748Y551968D03*
X159448D03*
X178346Y555119D03*
X178347Y564569D03*
X197245Y555118D03*
X190944D03*
X181497Y555120D03*
X172048Y564569D03*
X172047Y567717D03*
X175298Y577266D03*
X209842Y558268D03*
X190944Y589764D03*
Y592913D03*
X197244Y586615D03*
X200393Y586614D03*
X194094Y542519D03*
X209842Y564567D03*
X200393Y548819D03*
X209842Y561417D03*
Y589763D03*
X206692Y580315D03*
X209841D03*
X200393Y545669D03*
X206692Y545671D03*
X200393Y592913D03*
X159448Y589764D03*
Y592913D03*
X162598Y589764D03*
X165748D03*
Y592913D03*
X165749Y542519D03*
X175197Y592913D03*
X172048D03*
X209842Y555119D03*
Y551969D03*
X181497Y592913D03*
X197244Y545669D03*
X194094Y548820D03*
X209842Y548819D03*
X175197Y548821D03*
X168898Y545669D03*
X156300Y539371D03*
X194094Y545669D03*
X197244Y542520D03*
X194094Y602362D03*
X206692Y596063D03*
X194093D03*
X203605Y605450D03*
X200393Y596063D03*
X187795Y602363D03*
X153149Y605513D03*
X209841Y596063D03*
X190945Y599213D03*
X190944Y596063D03*
X187796Y599212D03*
X184645Y599213D03*
X159448Y596063D03*
X168898D03*
X203542Y602362D03*
Y599213D03*
X206692Y602362D03*
X203542Y596063D03*
X194094Y599213D03*
X162598Y596063D03*
X165748Y599213D03*
X168898D03*
X162598D03*
X159448D03*
X172048Y596063D03*
X178346Y596064D03*
X178347Y599213D03*
X181496Y596062D03*
X209841Y599212D03*
X206692Y599213D03*
X165748Y596063D03*
X175197D03*
Y599213D03*
X172048D03*
X219800Y445700D03*
X213874Y445226D03*
X216141Y580315D03*
X212992Y586614D03*
X216141Y577165D03*
X212991Y567718D03*
X216141Y583465D03*
Y586614D03*
Y564569D03*
X212992Y561417D03*
X216141Y567718D03*
X219293Y567717D03*
X212992Y580315D03*
X212991Y577165D03*
Y574016D03*
X216141D03*
Y561419D03*
X212991Y583465D03*
Y542519D03*
X212992Y589764D03*
Y555119D03*
Y558268D03*
X216142Y548820D03*
X216141Y555120D03*
Y558269D03*
X222441Y548820D03*
X219291D03*
X212992Y551969D03*
X216141Y551970D03*
X212992Y548819D03*
X216141Y589762D03*
X212993Y592912D03*
X212992Y564567D03*
Y545669D03*
X216142D03*
X222440Y605512D03*
X212992Y602363D03*
X212991Y599212D03*
X216141D03*
X762173Y294089D03*
X781088Y294094D03*
X771653Y294093D03*
X777952Y290944D03*
X777989Y294093D03*
X774802Y290944D03*
X774835Y294088D03*
X768503Y290944D03*
X768498Y294124D03*
X765353Y290944D03*
X765325Y294102D03*
X759054Y290944D03*
X759055Y294094D03*
X755905Y290944D03*
Y294093D03*
X787401Y290944D03*
X787408Y294074D03*
X784251Y290944D03*
X784258Y294064D03*
G54D108*
X495235Y42057D03*
G54D154*
G01X776378Y289370D02*
X777952Y290944D01*
G01X776378Y292519D02*
X776415D01*
X777989Y294093D01*
G01X773228Y289370D02*
X774802Y290944D01*
G01X773228Y292519D02*
X773266D01*
X774835Y294088D01*
G01X766929Y289370D02*
X768503Y290944D01*
G01X766929Y292519D02*
Y292555D01*
X768498Y294124D01*
G01X763779Y289370D02*
X765353Y290944D01*
G01X763779Y292519D02*
Y292556D01*
X765325Y294102D01*
G01X757480Y289370D02*
X759054Y290944D01*
G01X757480Y292519D02*
X759055Y294094D01*
G01X754331Y289370D02*
X755905Y290944D01*
G01X754331Y292519D02*
X755905Y294093D01*
G01X785827Y289370D02*
X787401Y290944D01*
G01X785827Y292519D02*
X785853D01*
X787408Y294074D01*
G01X782677Y289370D02*
X784251Y290944D01*
G01X782677Y292519D02*
X782713D01*
X784258Y294064D01*
G54D145*
G01X138900Y525999D02*
X116899D01*
X113800Y522900D01*
Y513800D01*
X116100Y511500D01*
X119400D01*
G01X135012Y510200D02*
X120700D01*
X119400Y511500D01*
G01X232300Y712600D02*
Y704300D01*
X229719Y701719D01*
X181409D01*
X167405Y687715D01*
X159349D01*
G01X320750Y586940D02*
X315121D01*
X314181Y586000D01*
G01X807006Y55812D02*
X804124D01*
X802786Y57150D01*
G54D25*
X40806Y543876D03*
X33358Y543881D03*
X40787Y555153D03*
X33287D03*
X40600Y549500D03*
X33100D03*
X40806Y538249D03*
X33258Y538254D03*
X40706Y532622D03*
X61346Y647850D03*
X127000Y534600D03*
X136900Y529700D03*
X137024Y538335D03*
X127000Y530300D03*
X120003Y609818D03*
X122997Y601923D03*
X122700Y632300D03*
Y636400D03*
X208700Y495300D03*
X197400Y502800D03*
X179520Y473998D03*
X153400Y648400D03*
X145149Y683715D03*
X155149Y711215D03*
X267900Y474500D03*
X248066Y567108D03*
X247700Y573500D03*
X247450Y578300D03*
X240300Y588900D03*
X239610Y537139D03*
X247700Y585700D03*
X239570Y552558D03*
X260800Y539500D03*
X264200Y552100D03*
X240596Y560698D03*
Y564798D03*
X254874Y552061D03*
X247996Y556761D03*
X248077Y563068D03*
X274300Y575000D03*
X224616Y658967D03*
X234800Y633200D03*
X239900Y601000D03*
X259873Y634343D03*
X272020Y718920D03*
X235500Y659100D03*
X258319Y662209D03*
X340217Y231156D03*
X340259Y261112D03*
X299032Y578108D03*
X293400Y573700D03*
X294100Y569700D03*
X291700Y565600D03*
X299200Y564200D03*
X299476Y557611D03*
X312633Y535357D03*
X302048Y620477D03*
X281960Y647950D03*
Y652100D03*
X291382Y691947D03*
X342229Y193678D03*
X366972Y245284D03*
X366842Y224934D03*
X367072Y240684D03*
X341978Y517086D03*
X347861Y507831D03*
X354630Y481570D03*
X345300Y545100D03*
X386300Y568500D03*
X387781Y623786D03*
X387700Y610300D03*
X362664Y635920D03*
X486600Y49100D03*
X489800Y34000D03*
X482400Y67973D03*
X482525Y58850D03*
X593500Y373300D03*
X604308Y373437D03*
X630322Y375305D03*
X646400Y504100D03*
X639460Y549543D03*
X696520Y197740D03*
X685100Y255400D03*
X696600Y244800D03*
X682000Y249100D03*
X693900Y228400D03*
Y232400D03*
Y236850D03*
X681447Y240430D03*
X685600Y265100D03*
X685200Y259500D03*
X696003Y211743D03*
X696150Y203560D03*
X685547Y277530D03*
Y269230D03*
X685400Y285900D03*
X685547Y281730D03*
X682800Y307000D03*
X685547Y273430D03*
X671150Y470684D03*
X672500Y503900D03*
X696000Y504000D03*
X703138Y553602D03*
X718600Y569100D03*
X707800Y614500D03*
X716176Y594029D03*
X754320Y126510D03*
X782554Y514350D03*
X785284Y505600D03*
X777300Y518500D03*
X767619Y488799D03*
X743800Y508600D03*
X819800Y322500D03*
X805934Y480900D03*
X865550Y403400D03*
G54D52*
X207900Y637900D03*
X200532Y653603D03*
X215406Y637892D03*
X227500Y642000D03*
X212445Y653488D03*
X272503Y704737D03*
X299900Y582200D03*
X296500D03*
X322277Y548643D03*
X282600Y682100D03*
X345175Y113910D03*
X366632Y192804D03*
X360800Y491700D03*
X477300Y61200D03*
X538250Y68490D03*
X617023Y372365D03*
X679200Y459200D03*
X727676Y587629D03*
X794088Y508612D03*
X763801Y488719D03*
X755300Y500700D03*
X763147Y496327D03*
X747500Y500900D03*
X882871Y236212D03*
G54D16*
X43480Y53750D03*
X71800Y691500D03*
X84616Y60475D03*
X93614Y507152D03*
X115619Y712795D03*
X295018Y661382D03*
X278523Y736205D03*
X353972Y192744D03*
X352980Y641914D03*
X453800Y61500D03*
X533940Y73210D03*
X563870Y55203D03*
X628160Y565343D03*
X612500Y540600D03*
X724900Y493800D03*
X720200D03*
X751500Y54030D03*
X767247Y502427D03*
X800388Y522956D03*
G54D109*
X525520Y63570D03*
Y77410D03*
X710330Y497490D03*
Y483650D03*
G54D43*
X135012Y521048D03*
X125788D03*
X135012Y514552D03*
X125788D03*
X270521Y612019D03*
Y618515D03*
X279745Y612019D03*
Y618515D03*
G54D70*
X339331Y91929D03*
X360669Y49803D03*
G54D127*
X628144Y531987D03*
X626176D03*
Y544099D03*
X628144D03*
G54D61*
X274245Y551954D03*
Y549394D03*
Y546834D03*
X281645D03*
Y549394D03*
Y551954D03*
G54D118*
X613087Y359016D03*
X615057D03*
X617027D03*
X618997D03*
Y349816D03*
X617027D03*
X615057D03*
X613087D03*
G54D34*
X43800Y660700D03*
X179518Y463748D03*
X145049Y687715D03*
X268300Y465400D03*
X251500Y590200D03*
X259707Y626253D03*
X268800Y639000D03*
X259100Y666100D03*
X325086Y522525D03*
X334200Y592000D03*
X278473Y637655D03*
X342100Y189874D03*
X366614Y639820D03*
X385170Y697180D03*
X468216Y53745D03*
X489786Y37907D03*
X774000Y66000D03*
X765900Y113000D03*
X837600Y475500D03*
G54D136*
X741114Y479374D03*
G54D155*
G01X297146Y280906D02*
X301808D01*
G01X297146Y277756D02*
X301808D01*
G01X297146Y306102D02*
X301808D01*
G01X297146Y302953D02*
X301809D01*
G54D146*
G01X203650Y495600D02*
X208350D01*
X208650Y495300D01*
G01X369500Y709940D02*
X373110D01*
X374430Y711260D01*
X376342D01*
G54D53*
X207900Y641500D03*
X200532Y657203D03*
X215406Y641492D03*
X227500Y645600D03*
X212445Y657088D03*
X272503Y708337D03*
X299900Y585800D03*
X296500D03*
X322277Y552243D03*
X282600Y685700D03*
X345175Y117510D03*
X366632Y196404D03*
X360800Y495300D03*
X477300Y64800D03*
X538250Y72090D03*
X617023Y375965D03*
X679200Y462800D03*
X727676Y591229D03*
X794088Y512212D03*
X763801Y492319D03*
X755300Y504300D03*
X763147Y499927D03*
X747500Y504500D03*
X882871Y239812D03*
G54D62*
X267250Y652500D03*
X259750Y648625D03*
Y656375D03*
X696100Y489716D03*
X688600Y493591D03*
Y485841D03*
X680250Y489500D03*
X672750Y493375D03*
Y485625D03*
X829970Y61300D03*
X822470Y65175D03*
Y57425D03*
G54D128*
X653700Y653200D03*
Y673400D03*
X678500Y653200D03*
Y673400D03*
G54D44*
X90854Y639150D03*
X98454D03*
X90854Y647050D03*
X98454D03*
X87050Y682154D03*
X94650D03*
X87100Y674400D03*
X94700D03*
X87900Y722700D03*
X95500D03*
X322740Y611500D03*
X330340D03*
X322740Y619400D03*
X330340D03*
X320774Y691270D03*
X328374D03*
X320774Y683370D03*
X328374D03*
X352200Y105700D03*
X359800D03*
X512857Y25444D03*
X520457D03*
X511349Y34452D03*
X503749D03*
Y42252D03*
X511349D03*
X602860Y528543D03*
X667600Y436900D03*
X660000D03*
X622300Y473000D03*
X614700D03*
X622300Y481000D03*
X614700D03*
X610460Y528543D03*
X669300Y704200D03*
X661700D03*
X669300Y696500D03*
X661700D03*
X669300Y688800D03*
X661700D03*
X721300Y433500D03*
X728900D03*
X721300Y441300D03*
X728900D03*
X721300Y449100D03*
X728900D03*
X721300Y456900D03*
X728900D03*
X721300Y464700D03*
X728900D03*
X684700Y536600D03*
X677100D03*
X683000Y567400D03*
X675400D03*
X684676Y559729D03*
X677076D03*
X684676Y544329D03*
X677076D03*
X684676Y552029D03*
X677076D03*
X683276Y579571D03*
X675676D03*
X835654Y481650D03*
X843254D03*
X835900Y469500D03*
X843500D03*
G54D71*
X297146Y199016D03*
Y195866D03*
Y192717D03*
X314666Y199016D03*
Y195866D03*
Y192717D03*
X297146Y265158D03*
Y262008D03*
Y258858D03*
Y255709D03*
Y252559D03*
Y249410D03*
Y246260D03*
Y243110D03*
Y239961D03*
Y236811D03*
Y233661D03*
Y230512D03*
Y227362D03*
Y224213D03*
Y221063D03*
Y217913D03*
Y214764D03*
Y211614D03*
Y208465D03*
Y205315D03*
Y202165D03*
X314666Y265158D03*
Y262008D03*
Y258858D03*
Y255709D03*
Y252559D03*
Y249410D03*
Y246260D03*
Y243110D03*
Y239961D03*
Y236811D03*
Y233661D03*
Y230512D03*
Y227362D03*
Y224213D03*
Y221063D03*
Y217913D03*
Y214764D03*
Y211614D03*
Y208465D03*
Y205315D03*
Y202165D03*
X297146Y328150D03*
Y325000D03*
Y321850D03*
Y318701D03*
Y315551D03*
Y312402D03*
Y309252D03*
Y306102D03*
Y302953D03*
Y299803D03*
Y296654D03*
Y293504D03*
Y290354D03*
Y287205D03*
Y284055D03*
Y280906D03*
Y277756D03*
Y274606D03*
Y271457D03*
Y268307D03*
X314666Y328150D03*
Y325000D03*
Y321850D03*
Y318701D03*
Y315551D03*
Y312402D03*
Y309252D03*
Y306102D03*
Y302953D03*
Y299803D03*
Y296654D03*
Y293504D03*
Y290354D03*
Y287205D03*
Y284055D03*
Y280906D03*
Y277756D03*
Y274606D03*
Y271457D03*
Y268307D03*
X297146Y378543D03*
Y375394D03*
Y372244D03*
Y369095D03*
Y365945D03*
Y362795D03*
Y359646D03*
Y356496D03*
Y353347D03*
Y350197D03*
Y347047D03*
Y343898D03*
Y340748D03*
Y337599D03*
Y334449D03*
Y331299D03*
X314666Y378543D03*
Y375394D03*
Y372244D03*
Y369095D03*
Y365945D03*
Y362795D03*
Y359646D03*
Y356496D03*
Y353347D03*
Y350197D03*
Y347047D03*
Y343898D03*
Y340748D03*
Y337599D03*
Y334449D03*
Y331299D03*
G54D137*
X752230Y485279D03*
Y483311D03*
Y481342D03*
Y479374D03*
X735414Y485279D03*
Y481342D03*
Y483311D03*
G54D80*
X374768Y53823D03*
Y49223D03*
X374594Y84695D03*
Y80095D03*
G54D35*
X47400Y660700D03*
X183118Y463748D03*
X148649Y687715D03*
X271900Y465400D03*
X255100Y590200D03*
X263307Y626253D03*
X272400Y639000D03*
X262700Y666100D03*
X328686Y522525D03*
X337800Y592000D03*
X282073Y637655D03*
X345700Y189874D03*
X370214Y639820D03*
X388770Y697180D03*
X471816Y53745D03*
X493386Y37907D03*
X777600Y66000D03*
X769500Y113000D03*
X841200Y475500D03*
G54D26*
X33265Y532638D03*
X61454Y639950D03*
X38733Y679946D03*
X131262Y603311D03*
X132018Y617677D03*
X131250Y599250D03*
X132753Y609777D03*
X109300Y597000D03*
Y601000D03*
Y609000D03*
Y605000D03*
Y613000D03*
X109800Y621000D03*
X109300Y617000D03*
X109899Y701465D03*
X137649Y687715D03*
X179544Y459767D03*
Y469867D03*
X174341Y495710D03*
X200200Y495600D03*
X208700Y499300D03*
X268000Y458200D03*
X268400Y490300D03*
X268000Y470300D03*
X239900Y581100D03*
X239570Y556658D03*
X263841Y543759D03*
X262900Y567300D03*
X266800Y572100D03*
X239618Y568821D03*
Y572821D03*
X240000Y576900D03*
X242293Y532802D03*
X273367Y557480D03*
X256220Y532870D03*
X267600Y605500D03*
X232900Y637600D03*
X266600Y643000D03*
X258300D03*
X259696Y630071D03*
X275450Y602700D03*
X267200Y723500D03*
X340247Y226992D03*
X340282Y256474D03*
X327121Y526309D03*
X291455Y546906D03*
X291500Y551300D03*
X326780Y531380D03*
X332465Y539609D03*
X326316Y543816D03*
X305051Y535356D03*
X287600Y617000D03*
X302000Y616384D03*
X291318Y684153D03*
X345631Y242261D03*
X345722Y247314D03*
X342794Y268585D03*
X343091Y272906D03*
X347800Y511900D03*
Y503600D03*
X387600Y589571D03*
X386579Y585543D03*
X386300Y576500D03*
Y572500D03*
X387700Y602100D03*
X387736Y619701D03*
X387700Y606200D03*
X387586Y628081D03*
X387550Y637348D03*
X385225Y693371D03*
X385700Y671800D03*
X388655Y684644D03*
X386200Y677900D03*
X434185Y38057D03*
X442616Y38147D03*
X437081Y56947D03*
X442685Y30457D03*
Y26157D03*
X442585Y21957D03*
X489800Y30000D03*
Y22000D03*
Y26000D03*
X525500Y49400D03*
Y53600D03*
X559300Y82000D03*
X630322Y379591D03*
X662200Y443200D03*
X639500Y553700D03*
X681642Y244547D03*
X694900Y249400D03*
X696100Y207600D03*
X720200Y564600D03*
Y560600D03*
X716176Y598329D03*
X767734Y518500D03*
X740100Y501300D03*
X811800Y322500D03*
X814572Y393639D03*
X814867Y398968D03*
X805900Y473500D03*
G54D119*
X615750Y463000D03*
X616250D03*
G54D17*
X43480Y48150D03*
X71800Y685900D03*
X84616Y54875D03*
X93614Y501552D03*
X115619Y707195D03*
X295018Y655782D03*
X278523Y730605D03*
X353972Y187144D03*
X352980Y636314D03*
X453800Y55900D03*
X533940Y67610D03*
X563870Y49603D03*
X628160Y559743D03*
X612500Y535000D03*
X724900Y488200D03*
X720200D03*
X751500Y48430D03*
X767247Y496827D03*
X800388Y517356D03*
G54D156*
G01X251314Y598106D02*
X250220Y599200D01*
X249733D01*
X244433Y593900D01*
X237885D01*
X231160Y587175D01*
X227769D01*
X223471Y582877D01*
X221853D01*
X220866Y581890D01*
G01X251338Y601506D02*
X250257Y600425D01*
X249225D01*
X243925Y595125D01*
X237377D01*
X230652Y588400D01*
X227261D01*
X222963Y584102D01*
X221803D01*
X220866Y585039D01*
G01Y588189D02*
X221352Y588675D01*
X222275D01*
X231000Y597400D01*
Y599087D01*
X238968Y607055D01*
X245672D01*
X247327Y605400D01*
X254233D01*
X256533Y607700D01*
X257377D01*
X258550Y606527D01*
G01X217716Y588189D02*
X219427Y589900D01*
X221767D01*
X229775Y597908D01*
Y599595D01*
X238460Y608280D01*
X246180D01*
X247835Y606625D01*
X253725D01*
X256025Y608925D01*
X257379D01*
X258550Y610096D01*
G01X301808Y280906D02*
X302756Y279958D01*
X306433D01*
G03X307567Y281092I0J1134D01*
G01X301808Y277756D02*
X302785Y278733D01*
X306426D01*
G02X307567Y277592I0J-1141D01*
G01X297146Y293504D02*
X300479D01*
X301454Y292529D01*
X303104D01*
G03X304267Y293692I0J1163D01*
G01X297146Y290354D02*
X300367D01*
X301317Y291304D01*
X303155D01*
G02X304267Y290192I0J-1112D01*
G01X301808Y306102D02*
X302736Y305174D01*
X306449D01*
G03X307567Y306292I0J1118D01*
G01X301809Y302953D02*
X302805Y303949D01*
X306449D01*
G02X307567Y302831I0J-1118D01*
G01Y302792D01*
G01X297146Y318701D02*
X300732D01*
X301682Y317751D01*
X303126D01*
G03X304267Y318892I0J1141D01*
G01X297146Y315551D02*
X300557D01*
X301532Y316526D01*
X303133D01*
G02X304267Y315392I0J-1134D01*
G01X297146Y331299D02*
X301081D01*
X301931Y330449D01*
X306482D01*
G03X307567Y331534I0J1085D01*
G01Y331592D01*
G01X297146Y328150D02*
X300558D01*
X301632Y329224D01*
X306482D01*
G02X307567Y328139I0J-1085D01*
G01Y328092D01*
G01X297146Y268307D02*
X301388D01*
X302310Y267385D01*
X303382D01*
G03X304231Y268234I0J849D01*
G01Y268548D01*
G01X297146Y265158D02*
X301366D01*
X302368Y266160D01*
X303382D01*
G02X304231Y265311I0J-849D01*
G01Y265048D01*
G01X314666Y287205D02*
X319336D01*
X320298Y286243D01*
X333541D01*
G03X334582Y287284I0J1041D01*
G01X314666Y284055D02*
X319335D01*
X320298Y285018D01*
X333482D01*
G02X334582Y283918I0J-1100D01*
G01Y283784D01*
G01X314666Y299803D02*
X319336D01*
X320299Y298840D01*
X327132D01*
G03X328182Y299890I0J1050D01*
G01Y299977D01*
G01X314666Y296654D02*
X319336D01*
X319337Y296653D01*
X320299Y297615D01*
X327132D01*
G02X328182Y296565I0J-1050D01*
G01Y296477D01*
G01X314666Y312402D02*
X319336D01*
X320299Y311439D01*
X333632D01*
G03X334582Y312389I0J950D01*
G01Y312574D01*
G01X314666Y309252D02*
X319337D01*
X320299Y310214D01*
X333632D01*
G02X334582Y309264I0J-950D01*
G01Y309074D01*
G01X314666Y325000D02*
X319336D01*
X320299Y324037D01*
X327182D01*
G03X328182Y325037I0J1000D01*
G01Y325174D01*
G01X314666Y321850D02*
X319337D01*
X320299Y322812D01*
X327182D01*
G02X328182Y321812I0J-1000D01*
G01Y321674D01*
G01X297146Y343898D02*
X300656D01*
X301606Y342948D01*
X303123D01*
G03X304267Y344092I0J1144D01*
G01X297146Y340748D02*
X300322D01*
X301297Y341723D01*
X303136D01*
G02X304267Y340592I0J-1131D01*
G01X297146Y356496D02*
X300850D01*
X301800Y355546D01*
X306421D01*
G03X307567Y356692I0J1146D01*
G01X297146Y353347D02*
X300446D01*
X301420Y354321D01*
X306438D01*
G02X307567Y353192I0J-1129D01*
G01X297146Y369095D02*
X300468D01*
X301418Y368145D01*
X303282D01*
G03X304267Y369130I0J985D01*
G01Y369292D01*
G01X297146Y365945D02*
X300510D01*
X301485Y366920D01*
X303282D01*
G02X304267Y365935I0J-985D01*
G01Y365792D01*
G01X314666Y337599D02*
X319336D01*
X320299Y336636D01*
X333782D01*
G03X334582Y337436I0J800D01*
G01Y337771D01*
G01X314666Y334449D02*
X319337D01*
X320299Y335411D01*
X333782D01*
G02X334582Y334611I0J-800D01*
G01Y334271D01*
G01X314666Y350197D02*
X319336D01*
X320299Y349234D01*
X327232D01*
G03X328182Y350184I0J950D01*
G01Y350371D01*
G01X314666Y347047D02*
X319337D01*
X320299Y348009D01*
X327232D01*
G02X328182Y347059I0J-950D01*
G01Y346871D01*
G01X314666Y362795D02*
X319336D01*
X320298Y361833D01*
X333482D01*
G03X334582Y362933I0J1100D01*
G01Y362974D01*
G01X314666Y359646D02*
X319336D01*
X320298Y360608D01*
X333482D01*
G02X334582Y359508I0J-1100D01*
G01Y359474D01*
G01X314666Y375394D02*
X319336D01*
X320299Y374431D01*
X327095D01*
G03X328182Y375518I0J1087D01*
G01X314666Y372244D02*
X319337D01*
X320299Y373206D01*
X326994D01*
G02X328182Y372018I0J-1188D01*
G01X340100Y631417D02*
X341336Y630181D01*
Y625605D01*
X348098Y618843D01*
X350565D01*
X350882Y618526D01*
X353864D01*
G01X339751Y616882D02*
X340987Y615646D01*
X346620D01*
X347212Y616238D01*
X350181D01*
X350500Y616557D01*
X353864D01*
G01X339751Y613185D02*
X340987Y614421D01*
X347128D01*
X347720Y615013D01*
X350316D01*
X350740Y614589D01*
X353864D01*
G01Y610651D02*
X350540D01*
X350169Y610280D01*
X346248D01*
X343080Y607112D01*
X338626D01*
X336272Y604758D01*
Y604275D01*
X335036Y603039D01*
G01X353864Y608683D02*
X350541D01*
X350169Y609055D01*
X346756D01*
X343588Y605887D01*
X339134D01*
X338115Y604868D01*
Y603657D01*
X338733Y603039D01*
G01X372000Y68650D02*
X372810Y67840D01*
X378960D01*
X379497Y67303D01*
X380402D01*
X381622Y66083D01*
Y65178D01*
X384468Y62332D01*
X387439D01*
X388014Y62907D01*
Y64437D01*
X386727Y65724D01*
Y67190D01*
G01X372000Y68650D02*
X371193Y67843D01*
X362542D01*
X361902Y68483D01*
X360177D01*
X359537Y67843D01*
X352218D01*
X349102Y70959D01*
X347133D01*
X346457Y71635D01*
Y74724D01*
G01X372000Y65750D02*
X372865Y66615D01*
X378452D01*
X383960Y61107D01*
X387947D01*
X389239Y62399D01*
Y64391D01*
X390527Y65679D01*
Y67190D01*
G01X372000Y65750D02*
X371132Y66618D01*
X352726D01*
X352725Y66617D01*
X351711D01*
X348594Y69734D01*
X347258D01*
X346457Y68933D01*
Y66850D01*
G01X386759Y79693D02*
X387889Y78563D01*
Y76009D01*
X386727Y74847D01*
Y73790D01*
G01X390456Y79693D02*
X389114Y78351D01*
Y76306D01*
X390527Y74893D01*
Y73790D01*
G01X450000Y178740D02*
Y177046D01*
X450478Y176568D01*
X452533D01*
X453928Y175173D01*
Y91130D01*
X449234Y86436D01*
X435851D01*
X423964Y98323D01*
X411669D01*
X402539Y107453D01*
Y158915D01*
X402109Y159345D01*
X401341D01*
X400205Y158209D01*
G01X450000Y173229D02*
Y174823D01*
X450520Y175343D01*
X452025D01*
X452703Y174665D01*
Y91638D01*
X448726Y87661D01*
X436359D01*
X424472Y99548D01*
X412177D01*
X403764Y107961D01*
Y159423D01*
X402617Y160570D01*
X401541D01*
X400205Y161906D01*
G01X343797Y631417D02*
X342561Y630181D01*
Y626113D01*
X348606Y620068D01*
X350519D01*
X350945Y620494D01*
X353514D01*
G01X384158Y638105D02*
X382945Y636892D01*
Y635477D01*
X379683Y632215D01*
X370990D01*
X368507Y629732D01*
Y627780D01*
X369101Y627186D01*
Y623920D01*
G01X380443Y638105D02*
X381720Y636828D01*
Y635985D01*
X379175Y633440D01*
X370482D01*
X367282Y630240D01*
Y627335D01*
X367133Y627186D01*
Y623920D01*
G01X527953Y174016D02*
Y173053D01*
X526761Y171861D01*
X525055D01*
X523854Y170660D01*
Y107903D01*
X522651Y106700D01*
X520900D01*
X520000Y107600D01*
Y108700D01*
G01X527953Y168504D02*
Y169447D01*
X526764Y170636D01*
X525563D01*
X525079Y170152D01*
Y107395D01*
X523159Y105475D01*
X520607D01*
X519900Y104768D01*
Y103150D01*
G01X776378Y298819D02*
X776058D01*
X774877Y300000D01*
Y309492D01*
X782876Y317491D01*
Y335798D01*
X777375Y341299D01*
Y346242D01*
X780266Y349133D01*
G03Y350734I-801J801D01*
G01X780263Y350737D01*
G01X782737Y348263D02*
X782733Y348267D01*
G03X781133I-800J-800D01*
G01X778600Y345734D01*
Y341807D01*
X784101Y336306D01*
Y316983D01*
X776102Y308984D01*
Y302244D01*
X776378Y301968D01*
G01X775181Y338437D02*
G02Y336830I-803J-804D01*
G01X773775Y335424D01*
Y333492D01*
X775692Y331575D01*
X776351Y330917D01*
Y317931D01*
X771727Y313307D01*
Y300000D01*
X772908Y298819D01*
X773228D01*
G01X777655Y335963D02*
G03X776047I-804J-804D01*
G01X775000Y334916D01*
Y334000D01*
X777576Y331425D01*
Y317423D01*
X772952Y312799D01*
Y302244D01*
X773228Y301968D01*
G01X766929Y298819D02*
X766781D01*
X765324Y300276D01*
Y313904D01*
X771300Y319880D01*
Y329467D01*
X760075Y340692D01*
Y345824D01*
X763081Y348830D01*
G03Y350437I-803J804D01*
G01X765555Y347963D02*
G03X763947I-804J-804D01*
G01X761300Y345316D01*
Y341200D01*
X772525Y329975D01*
Y319372D01*
X766549Y313396D01*
Y302348D01*
X766929Y301968D01*
G01X763779Y298819D02*
X763531D01*
X762052Y300298D01*
Y310209D01*
X760775Y311486D01*
Y327043D01*
X760943Y327210D01*
X763966Y330233D01*
G03Y331834I-800J801D01*
G01X763963Y331837D01*
G01X766437Y329363D02*
X766433Y329367D01*
G03X764833I-800J-800D01*
G01X762000Y326534D01*
Y311994D01*
X763277Y310717D01*
Y302470D01*
X763779Y301968D01*
G01X757480Y298819D02*
X757128D01*
X756047Y299900D01*
Y329699D01*
X749975Y335771D01*
Y339742D01*
X752363Y342130D01*
G03Y343737I-803J803D01*
G01X754837Y341263D02*
G03X753229I-804J-804D01*
G01X751200Y339234D01*
Y336279D01*
X757272Y330207D01*
Y302176D01*
X757480Y301968D01*
G01X754331Y298819D02*
X754200D01*
X752669Y300350D01*
Y310650D01*
X750675Y312644D01*
Y321992D01*
X744975Y327692D01*
Y329842D01*
X746466Y331333D01*
G03Y332534I-601J601D01*
G01X746263Y332737D01*
G01X748737Y330263D02*
X748533Y330467D01*
G03X747333I-600J-600D01*
G01X746200Y329334D01*
Y328200D01*
X751900Y322500D01*
Y313152D01*
X753894Y311158D01*
Y302405D01*
X754331Y301968D01*
G01X802363Y336637D02*
X802465Y336535D01*
G02Y335135I-700J-700D01*
G01X801165Y333835D01*
X799000Y331668D01*
Y319513D01*
X784602Y305115D01*
Y302680D01*
X784300Y302378D01*
Y300346D01*
X785827Y298819D01*
G01X804837Y334163D02*
X804732Y334268D01*
G03X803332I-700J-700D01*
G01X802432Y333368D01*
X800225Y331160D01*
Y319005D01*
X785827Y304607D01*
Y301968D01*
G01X792163Y338937D02*
G02Y337330I-803J-804D01*
G01X788047Y333214D01*
X787879Y333047D01*
Y313477D01*
X781310Y306908D01*
Y302564D01*
X781200Y302454D01*
Y300700D01*
X782677Y298819D01*
G01X794637Y336463D02*
G03X793029I-804J-804D01*
G01X789104Y332538D01*
Y312969D01*
X782535Y306400D01*
Y302110D01*
X782677Y301968D01*
G01X815250Y322500D02*
X817075Y320675D01*
Y319006D01*
X813476Y315407D01*
X802234D01*
X793101Y306274D01*
Y302943D01*
X792126Y301968D01*
G01X819750Y322500D02*
X818300Y321050D01*
Y318498D01*
X813984Y314182D01*
X802742D01*
X794326Y305766D01*
Y302917D01*
X795275Y301968D01*
G01X820343Y333496D02*
G02Y331889I-803J-804D01*
G01X819207Y330753D01*
X816766Y328310D01*
Y324016D01*
X815250Y322500D01*
G01X822817Y331022D02*
G03X821210I-803J-803D01*
G01X820074Y329886D01*
X817991Y327802D01*
Y324258D01*
X819750Y322500D01*
G54D147*
G01X157874Y562992D02*
X157871D01*
X156820Y561941D01*
G02X155176Y561260I-1644J1643D01*
G01X158795Y564566D02*
G03X159904Y565026I0J1567D01*
G01X161021Y566142D01*
X161023D01*
G01X157874Y569291D02*
X157721D01*
G03X156695Y568866I0J-1451D01*
G01X156195Y568366D01*
X156020Y568190D01*
G02X154995Y567766I-1025J1027D01*
G54D54*
X163189Y669291D03*
G54D129*
X720039Y422909D03*
X704539D03*
G54D72*
X305070Y522451D03*
Y525011D03*
X317870D03*
Y522451D03*
X305070Y527571D03*
Y530131D03*
X317870D03*
Y527571D03*
X313821Y556747D03*
Y559307D03*
Y561867D03*
Y564427D03*
Y566987D03*
Y569547D03*
Y572107D03*
Y574667D03*
Y577227D03*
Y579787D03*
X336021D03*
Y577227D03*
Y574667D03*
Y572107D03*
Y569547D03*
Y566987D03*
Y564427D03*
Y561867D03*
Y559307D03*
Y556747D03*
X355739Y575709D03*
Y573149D03*
Y570589D03*
Y568029D03*
Y565469D03*
Y562909D03*
Y560349D03*
Y557789D03*
Y555229D03*
Y552669D03*
Y550109D03*
Y547549D03*
X377939D03*
Y550109D03*
Y552669D03*
Y555229D03*
Y557789D03*
Y560349D03*
Y562909D03*
Y565469D03*
Y568029D03*
Y570589D03*
Y573149D03*
Y575709D03*
X374610Y695500D03*
Y692940D03*
Y690380D03*
Y687820D03*
Y685260D03*
Y682700D03*
Y680140D03*
Y677580D03*
Y675020D03*
Y672460D03*
X352410D03*
Y675020D03*
Y677580D03*
Y680140D03*
Y682700D03*
Y685260D03*
Y687820D03*
Y690380D03*
Y692940D03*
Y695500D03*
G54D138*
X750712Y488766D03*
X748743D03*
X738901D03*
X736932D03*
X740869D03*
X742838D03*
X744806D03*
X746775D03*
G54D36*
X49900Y674984D03*
X117700Y518800D03*
X85500Y636300D03*
X81784Y671500D03*
X203650Y636650D03*
X207060Y633220D03*
X170100Y708200D03*
X210520Y632910D03*
X247400Y643000D03*
X225400Y716600D03*
X263000Y679300D03*
X328659Y539659D03*
X317600Y610400D03*
X322100Y645300D03*
X314920Y682520D03*
X311704Y715720D03*
X366699Y204821D03*
X521800Y53400D03*
X559200Y44100D03*
X633800Y341500D03*
X614000Y340900D03*
X645300Y529800D03*
X702460Y484650D03*
X728559Y477898D03*
X676194Y589729D03*
X723676Y591229D03*
X776200Y54800D03*
X786600Y419800D03*
X794500Y501200D03*
X757099Y526566D03*
X826284Y505500D03*
X883100Y224700D03*
G54D27*
X36665Y532638D03*
X64854Y639950D03*
X42133Y679946D03*
X134662Y603311D03*
X135418Y617677D03*
X134650Y599250D03*
X136153Y609777D03*
X112700Y597000D03*
Y601000D03*
Y609000D03*
Y605000D03*
Y613000D03*
X113200Y621000D03*
X112700Y617000D03*
X113299Y701465D03*
X141049Y687715D03*
X182944Y459767D03*
Y469867D03*
X177741Y495710D03*
X203600Y495600D03*
X271400Y458200D03*
X271800Y490300D03*
X271400Y470300D03*
X212100Y499300D03*
X243300Y581100D03*
X242970Y556658D03*
X267241Y543759D03*
X266300Y567300D03*
X270200Y572100D03*
X243018Y568821D03*
Y572821D03*
X243400Y576900D03*
X245693Y532802D03*
X259620Y532870D03*
X271000Y605500D03*
X236300Y637600D03*
X270000Y643000D03*
X261700D03*
X263096Y630071D03*
X270600Y723500D03*
X330521Y526309D03*
X294855Y546906D03*
X294900Y551300D03*
X276767Y557480D03*
X330180Y531380D03*
X335865Y539609D03*
X329716Y543816D03*
X308451Y535356D03*
X291000Y617000D03*
X305400Y616384D03*
X278850Y602700D03*
X294718Y684153D03*
X343647Y226992D03*
X349031Y242261D03*
X349122Y247314D03*
X343682Y256474D03*
X346194Y268585D03*
X346491Y272906D03*
X351200Y511900D03*
Y503600D03*
X391000Y589571D03*
X389979Y585543D03*
X389700Y576500D03*
Y572500D03*
X391100Y602100D03*
X391136Y619701D03*
X391100Y606200D03*
X390986Y628081D03*
X390950Y637348D03*
X388625Y693371D03*
X389100Y671800D03*
X392055Y684644D03*
X389600Y677900D03*
X437585Y38057D03*
X446016Y38147D03*
X440481Y56947D03*
X446085Y30457D03*
Y26157D03*
X445985Y21957D03*
X493200Y30000D03*
Y22000D03*
Y26000D03*
X528900Y49400D03*
Y53600D03*
X562700Y82000D03*
X633722Y379591D03*
X665600Y443200D03*
X642900Y553700D03*
X685042Y244547D03*
X698300Y249400D03*
X699500Y207600D03*
X723600Y564600D03*
Y560600D03*
X719576Y598329D03*
X771134Y518500D03*
X743500Y501300D03*
X815200Y322500D03*
X817972Y393639D03*
X818267Y398968D03*
X809300Y473500D03*
G54D81*
X372000Y68900D03*
G54D90*
X369969Y580758D03*
X507322Y22393D03*
X502622D03*
X582090Y48880D03*
X646377Y406737D03*
X642660Y562243D03*
X708000Y451700D03*
X675174Y459279D03*
X731076Y595829D03*
X782500Y415200D03*
X762400Y473100D03*
X885562Y307955D03*
X880223Y384817D03*
G54D63*
X244750Y652500D03*
X252250Y656375D03*
Y648625D03*
X244750Y666500D03*
X252250Y662625D03*
Y670375D03*
X359976Y183681D03*
X367476Y179806D03*
Y187556D03*
X491740Y63670D03*
X499240Y67545D03*
Y59795D03*
X683000Y473384D03*
X690500Y469509D03*
Y477259D03*
G54D45*
X135522Y628682D03*
X83000Y734600D03*
X252107Y516929D03*
X689237Y325511D03*
X838300Y36700D03*
X820896Y207364D03*
X888800Y696900D03*
G54D18*
G01X43480Y53950D02*
X43510Y53980D01*
Y57810D01*
G01X275100Y460300D02*
Y457115D01*
X273685Y455700D01*
X263000D01*
X262000Y456700D01*
X202037D01*
X192637Y447300D01*
X59600D01*
X22100Y484800D01*
Y665300D01*
X34300Y677500D01*
G01X66278Y550242D02*
X62527D01*
X62276Y550493D01*
G01X69427Y581738D02*
X67852Y583313D01*
G01X72577Y572290D02*
X75050D01*
X75197Y572437D01*
G01X66278Y547093D02*
X61493D01*
X61100Y546700D01*
G01X69427Y559691D02*
Y559692D01*
X67853Y561266D01*
G01X66278Y575439D02*
Y575440D01*
X67853Y577015D01*
G01X66278Y578589D02*
X66279D01*
X67853Y577015D01*
G01X64884Y650984D02*
X63155Y652713D01*
Y656107D01*
G01X47350Y660700D02*
Y658550D01*
X49300Y656600D01*
G01X55971Y660732D02*
X53432D01*
X49300Y656600D01*
G01X34300Y677500D02*
X36746Y679946D01*
X38683D01*
G01X63155Y675593D02*
Y679455D01*
X66800Y683100D01*
X70864D01*
X71014Y682950D01*
X77129D01*
X77179Y683000D01*
X78150D01*
X80600Y685450D01*
G01X76100Y690250D02*
X76600Y689750D01*
Y686300D01*
X76264Y685964D01*
G01X60596Y675593D02*
Y680596D01*
X66400Y686400D01*
X71100D01*
X71800Y685700D01*
G01X76264Y685964D02*
X75800Y685500D01*
X72000D01*
X71800Y685700D01*
G01X49900Y674934D02*
X46200D01*
X46100Y675034D01*
G01X49900Y674934D02*
X53465D01*
X55971Y672428D01*
Y670968D01*
G01X46043Y679557D02*
X45654Y679946D01*
X42183D01*
G01X46100Y675034D02*
Y679500D01*
X46043Y679557D01*
G01X136974Y538335D02*
Y535251D01*
X136990Y535235D01*
G01X91474Y556542D02*
X91472D01*
X89899Y558115D01*
G01X91474Y578589D02*
Y578588D01*
X93048Y577014D01*
G01X91474Y559691D02*
X91473D01*
X89899Y561265D01*
G01X122650Y632300D02*
Y629350D01*
X122000Y628700D01*
G01X123900Y651450D02*
Y655500D01*
X125100Y656700D01*
G01X125376Y708939D02*
X122239D01*
X118849Y705549D01*
Y703715D01*
X117767Y702633D01*
G01X113349Y697097D02*
Y701465D01*
G01D02*
X116599D01*
X117767Y702633D01*
G01X111200Y709850D02*
X109484D01*
X106879Y707245D01*
G01X125376Y701124D02*
Y705002D01*
G01X121549Y694797D02*
X125376Y698624D01*
Y701124D01*
G01X117449Y697097D02*
X119549D01*
X121501Y699049D01*
G01X125376Y706971D02*
X123105D01*
X121501Y705367D01*
Y699049D01*
G01X141099Y687715D02*
Y685259D01*
X142681Y683677D01*
X145061D01*
X145099Y683715D01*
G01X125376Y712876D02*
X115738D01*
X115619Y712995D01*
G01D02*
X111555D01*
X111200Y713350D01*
G01D02*
X108960D01*
X106355Y710745D01*
G01X109849Y701465D02*
X106635D01*
G01X80600Y685450D02*
X81343D01*
X83893Y688000D01*
X84600D01*
G01X119849Y709715D02*
X121042Y710908D01*
X125376D01*
G01X188400Y506350D02*
Y506963D01*
X191418Y509981D01*
G01X197243Y589764D02*
X195669Y588190D01*
Y588189D01*
G01X208267Y591338D02*
X206692Y592913D01*
G01X186220Y540945D02*
X184645Y539370D01*
G01X192519Y540945D02*
X194094Y539370D01*
G01X157874Y566142D02*
X159449Y567717D01*
G01X194093Y555120D02*
X194092D01*
X192519Y556693D01*
G01X197243Y539371D02*
X195669Y537797D01*
Y537795D01*
G01X194094Y539370D02*
X192519Y537795D01*
G01X184645Y539370D02*
X186220Y537795D01*
G01X197243Y551970D02*
X195670Y553543D01*
X195669D01*
G01X194093Y551970D02*
X192520Y553543D01*
X192519D01*
G01X187795Y555120D02*
X189368Y556693D01*
X189370D01*
G01X205118Y575590D02*
X205116D01*
X203543Y574017D01*
G01D02*
X205118Y572442D01*
Y572441D01*
G01Y585039D02*
X206692Y583465D01*
G01D02*
X205118Y581891D01*
Y581890D01*
G01Y588189D02*
X205117D01*
X203542Y586614D01*
G01D02*
X201968Y585040D01*
Y585039D01*
G01Y581890D02*
Y581889D01*
X203542Y580315D01*
G01D02*
X201968Y578741D01*
Y578740D01*
G01X179921D02*
X179918D01*
X178344Y577166D01*
G01X179921Y585039D02*
Y585040D01*
X178346Y586615D01*
G01D02*
X176771Y585040D01*
Y585039D01*
G01X183071D02*
Y585040D01*
X181497Y586614D01*
G01X179921Y575590D02*
X179919D01*
X178347Y574018D01*
G01D02*
X179921Y572444D01*
Y572441D01*
G01X178347Y570868D02*
X179921Y569294D01*
Y569291D01*
G01X189370Y585039D02*
X190944Y586613D01*
Y586614D01*
G01X201968Y572441D02*
Y572440D01*
X200394Y570866D01*
G01D02*
X201968Y569292D01*
Y569291D01*
G01Y575590D02*
X200394Y574016D01*
G01X201968Y559842D02*
Y559843D01*
X203543Y561418D01*
G01D02*
X203542D01*
X201968Y562992D01*
G01X203543Y564568D02*
X203542D01*
X201968Y566142D01*
G01X167323Y553543D02*
X165748Y551968D01*
G01X157874Y553543D02*
Y553542D01*
X159448Y551968D01*
G01X176771Y556693D02*
X176772D01*
X178346Y555119D01*
G01X179921Y566142D02*
X179920D01*
X178347Y564569D01*
G01D02*
X179921Y562995D01*
Y562992D01*
G01X195669Y556693D02*
X195670D01*
X197245Y555118D01*
G01D02*
X198819Y556692D01*
Y556693D01*
G01X190944Y555118D02*
X189370Y553544D01*
Y553543D01*
G01X179921Y556693D02*
X179924D01*
X181497Y555120D01*
G01D02*
X183070Y556693D01*
X183071D01*
G01X190944Y592913D02*
Y592912D01*
X189370Y591338D01*
G01X190944Y589764D02*
Y589763D01*
X189370Y588189D01*
G01X200393Y586614D02*
X198819Y585040D01*
Y585039D01*
G01X197244Y586615D02*
X195669Y585040D01*
Y585039D01*
G01X186220Y600787D02*
X187795Y602362D01*
Y602363D01*
G01X168900Y637050D02*
X169000Y637150D01*
Y640300D01*
G01X187795Y602363D02*
X187794D01*
X186220Y603937D01*
G01X209841Y596063D02*
Y596062D01*
X208267Y594488D01*
G01X164349Y698865D02*
X160549D01*
X160249Y699165D01*
G01D02*
X155849D01*
G01X151749D02*
X150335D01*
X148349Y701151D01*
Y706215D01*
X147593Y706971D01*
X144662D01*
G01X155849Y699165D02*
X151749D01*
G01X156657Y726500D02*
X165700D01*
X167500Y724700D01*
Y709350D01*
X166400Y708250D01*
G01X148650Y691600D02*
X151834D01*
X151949Y691715D01*
G01X166400Y704750D02*
X166500Y704650D01*
X170100D01*
G01D02*
X174965D01*
X175233Y704382D01*
G01X178543Y726500D02*
X170900D01*
X169300Y724900D01*
Y708950D01*
X170100Y708150D01*
G01X155099Y711215D02*
X153849D01*
X152188Y712876D01*
X144662D01*
G01Y705002D02*
Y697593D01*
G01X145099Y687715D02*
X145150Y687766D01*
Y691600D01*
G01D02*
Y695864D01*
X144662Y696352D01*
Y697593D01*
G01X145099Y683715D02*
Y687715D01*
G01X153349D02*
X148599D01*
G01D02*
Y683715D01*
G01X158349Y703465D02*
X162599D01*
X163349Y702715D01*
G01X150849Y710215D02*
X150156Y710908D01*
X144662D01*
G01Y708939D02*
X148625D01*
X150599Y706965D01*
X154300D01*
G01D02*
X158349D01*
G01D02*
X158449Y707065D01*
X163183D01*
X163260Y706988D01*
G01X164349Y695365D02*
X168215D01*
X169070Y696220D01*
G01X221225Y490300D02*
X220521D01*
G01X212600Y516950D02*
Y514400D01*
X211700Y513500D01*
G01X216900Y512216D02*
X218916D01*
X220100Y513400D01*
G01X211196Y487762D02*
X213734Y490300D01*
X220521D01*
G01X269900Y567619D02*
X269681Y567400D01*
X269200D01*
X269100Y567300D01*
X266350D01*
G01X222500Y536161D02*
X220866Y537795D01*
G01X243060Y537139D02*
X243444Y537523D01*
X246100D01*
X246484Y537139D01*
G01X243750Y588900D02*
X244450Y589600D01*
X247400D01*
G01X255050Y590200D02*
X260800D01*
X261900Y591300D01*
G01X275470Y608480D02*
X292123D01*
X294960Y611317D01*
Y621530D01*
X291030Y625460D01*
X272990D01*
X270400Y622870D01*
G01X266571Y608619D02*
X266400Y608790D01*
Y608900D01*
X265070Y610230D01*
Y621290D01*
X266650Y622870D01*
X270400D01*
G01X216600Y658400D02*
X216400D01*
X215038Y657038D01*
X212445D01*
G01X246500Y601500D02*
X246400D01*
X245900Y601000D01*
X243350D01*
G01X219200Y644050D02*
Y647200D01*
G01X222440Y605512D02*
X220866Y603938D01*
Y603937D01*
G01X263323Y634343D02*
X266857D01*
G01X245300Y635700D02*
X245600D01*
X247400Y637500D01*
Y639450D01*
G01X272200Y648550D02*
X273685Y650035D01*
Y650533D01*
X275500Y652348D01*
G01X242000Y693400D02*
X242626Y692774D01*
X245971D01*
G01X267150Y723500D02*
X263700D01*
G01X275349D02*
X270650D01*
G01X272503Y708287D02*
X273906D01*
X276325Y705868D01*
Y705863D01*
G01X349206Y129948D02*
X333544D01*
X325442Y121846D01*
Y35798D01*
X326553Y34687D01*
G01X314666Y217913D02*
X319843D01*
X321782Y215974D01*
G01X314666Y214764D02*
X320572D01*
X321782Y215974D01*
G01X297146Y249410D02*
X303546D01*
X305082Y247874D01*
X306446D01*
G01X297146Y214764D02*
X303292D01*
X304232Y213824D01*
X305498D01*
G01D02*
X303288Y211614D01*
X297146D01*
G01X314666Y268307D02*
Y268308D01*
G01X297146Y271457D02*
X303140D01*
X304231Y272548D01*
G01X314666Y378543D02*
X319545D01*
X321202Y376886D01*
Y376887D01*
G01X305070Y525011D02*
X298611D01*
X298350Y524750D01*
G01X336021Y579787D02*
X330983D01*
X327110Y583660D01*
G01X337750Y592000D02*
Y589739D01*
X337899Y589590D01*
Y587874D01*
G01X310350Y538293D02*
X308228Y540415D01*
X306052D01*
G01X305470Y623734D02*
X303741Y625463D01*
Y628857D01*
G01X335311Y656480D02*
X337240Y658409D01*
X339266D01*
G01X275500Y652348D02*
X279612D01*
X279860Y652100D01*
X281910D01*
G01X295018Y655582D02*
X295400Y655200D01*
Y650100D01*
X297157Y648343D01*
X301182D01*
G01X289800Y660450D02*
Y656614D01*
X290399Y656015D01*
G01D02*
X290832Y655582D01*
X295018D01*
G01X296557Y643718D02*
X285942D01*
X285410Y644250D01*
G01Y647950D02*
Y644250D01*
G01Y652100D02*
X289037D01*
X289917Y651220D01*
Y649778D01*
G01X285410Y647950D02*
X288698D01*
X289917Y649169D01*
Y649778D01*
G01X285988Y637449D02*
X285782Y637655D01*
X282023D01*
G01X296557Y633482D02*
X289955D01*
X285988Y637449D01*
G01X294804Y695204D02*
X293075Y696933D01*
Y700327D01*
G01X318400Y678400D02*
X315490D01*
X314920Y678970D01*
G01X340100Y718200D02*
Y717200D01*
X347300Y710000D01*
X353020D01*
X356820Y706200D01*
X369500D01*
G01X291700Y730150D02*
X293075Y728775D01*
Y719813D01*
G01X290516D02*
Y722948D01*
X287400Y726064D01*
Y729386D01*
X287620Y729606D01*
Y730170D01*
G01X275470Y718920D02*
Y723379D01*
X275349Y723500D01*
G01X285891Y715188D02*
X275638D01*
X275550Y715100D01*
G01X275470Y718920D02*
Y715180D01*
X275550Y715100D01*
G01X285891Y704952D02*
X277241D01*
X276330Y705863D01*
X276325D01*
G01X290000Y727000D02*
X289900Y727100D01*
Y728350D01*
X291700Y730150D01*
G01X278523Y730405D02*
X283062D01*
X283080Y730387D01*
G01X287620Y730170D02*
X287403Y730387D01*
X283080D01*
G01X366632Y196354D02*
Y201204D01*
X366699Y201271D01*
G01X363975Y217923D02*
Y220290D01*
X362197Y222068D01*
G01X366699Y201271D02*
X371081D01*
X371775Y200577D01*
G01X341882Y251064D02*
X349032D01*
X349106Y251138D01*
X351036D01*
X363127Y263229D01*
Y342327D01*
X365200Y344400D01*
G01X344700Y509000D02*
X345000Y509300D01*
Y509540D01*
X347360Y511900D01*
X347750D01*
G01X365800Y498300D02*
X363800D01*
X360800Y495300D01*
Y495250D01*
G01X361439Y509869D02*
X357462D01*
X357224Y510107D01*
X355307D01*
X355300Y510100D01*
G01X371460Y487050D02*
Y484830D01*
X371650Y484640D01*
Y481798D01*
X371900Y481548D01*
G01X369300Y508700D02*
X373096D01*
X374265Y509869D01*
X377739D01*
G01X350000Y528950D02*
X346803D01*
X345497Y527644D01*
G01X372600Y576207D02*
X371925Y576882D01*
Y577367D01*
X369969Y579323D01*
Y580558D01*
G01X373500Y540305D02*
X373605D01*
X374212Y540912D01*
X374962D01*
X377250Y543200D01*
G01X351600Y540600D02*
X348750Y543450D01*
Y545100D01*
G01X363008Y547309D02*
X362917Y547400D01*
X360225D01*
X360076Y547549D01*
X355739D01*
G01X374292Y583350D02*
Y580300D01*
G01X359258Y601320D02*
Y596820D01*
G01X359036Y639880D02*
Y635900D01*
G01X370164Y639820D02*
Y636436D01*
X370200Y636400D01*
G01X360049Y651827D02*
X355333D01*
X355000Y652160D01*
G01D02*
Y645294D01*
X356200Y644094D01*
Y642716D01*
X359036Y639880D01*
G01X350500Y647600D02*
Y646400D01*
X352980Y643920D01*
Y642114D01*
G01X348600Y643500D02*
Y639050D01*
G01X348000Y612661D02*
X348041Y612620D01*
X353864D01*
G01X357290Y600970D02*
X352720D01*
G01X357290Y624270D02*
X354232D01*
X352400Y626102D01*
G01X372408Y629626D02*
X371070Y628288D01*
Y623920D01*
G01X367133Y601320D02*
Y596067D01*
G01X376464Y612620D02*
X382037D01*
X382380Y612277D01*
G01X473151Y50052D02*
X472852D01*
X470953Y48153D01*
Y45150D01*
G01X469058Y49156D02*
X468984Y49082D01*
Y45150D01*
G01X453800Y55700D02*
X456174Y53326D01*
X458662D01*
G01X465047Y45150D02*
Y54703D01*
X464100Y55650D01*
X463200D01*
G01X458662Y53326D02*
X460986Y55650D01*
X463200D01*
G01X493250Y30000D02*
X494600D01*
X496700Y32100D01*
G01X493250Y34000D02*
X494800D01*
X496700Y32100D01*
G01X482693Y42200D02*
X481900D01*
X480021Y40321D01*
X477750D01*
G01X490035Y42057D02*
Y45450D01*
X490050Y45465D01*
Y45900D01*
G01D02*
Y49100D01*
G01X512806Y49494D02*
X512962Y49650D01*
X516600D01*
G01X521800Y49850D02*
X525000D01*
X525450Y49400D01*
G01X521800Y49850D02*
X516800D01*
X516600Y49650D01*
G01X521200Y57600D02*
X519100D01*
X517825Y56325D01*
Y54994D01*
G01X525450Y53600D02*
X522050D01*
X521800Y53350D01*
G01X517825Y54994D02*
X519469Y53350D01*
X521800D01*
G01X472000Y35500D02*
X474853Y38353D01*
X477750D01*
G01X493336Y37907D02*
Y39358D01*
X496035Y42057D01*
G01D02*
Y46435D01*
G01X571040Y62835D02*
X567535D01*
X565100Y60400D01*
G01X563870Y55403D02*
Y59170D01*
X565100Y60400D01*
G01X564100Y44203D02*
Y25112D01*
X564803Y24409D01*
G01X563870Y49403D02*
Y44433D01*
X564100Y44203D01*
G01X581476Y43046D02*
Y27736D01*
X584803Y24409D01*
G01X582090Y48680D02*
Y43660D01*
X581476Y43046D01*
G01X576160Y54765D02*
Y57710D01*
X577230Y58780D01*
X582090D01*
G01Y54680D02*
Y58780D01*
G01X582219Y386612D02*
X582568Y386961D01*
X585998D01*
G01X593450Y373300D02*
X588676D01*
G01X589873Y379461D02*
X598361D01*
X605861Y386961D01*
X607748D01*
G01X588676Y373300D02*
X588076Y373900D01*
Y377664D01*
X589873Y379461D01*
G01X617023Y375915D02*
X616363Y376575D01*
Y379468D01*
X616428Y379533D01*
G01X625894Y347800D02*
Y343756D01*
X629900Y339750D01*
Y339300D01*
G01X612300Y344300D02*
X613150D01*
X615057Y346207D01*
Y349816D01*
G01X630108Y343242D02*
X628454Y344896D01*
Y347800D01*
G01Y360600D02*
Y355860D01*
X627832Y355238D01*
X626418D01*
X625894Y355762D01*
Y360600D01*
G01X630272Y368128D02*
Y366940D01*
X628454Y365122D01*
Y360600D01*
G01X630272Y368128D02*
Y375305D01*
G01D02*
X627109D01*
X626262Y376152D01*
Y377540D01*
G01D02*
Y378834D01*
X627019Y379591D01*
X630272D01*
G01X625100Y494148D02*
Y494326D01*
G01D02*
Y499800D01*
X626100Y500800D01*
X645500D01*
X646700Y499600D01*
G01X616250Y463000D02*
X619655D01*
G01X654300Y504100D02*
X649850D01*
G01D02*
Y502690D01*
X652700Y499840D01*
Y499600D01*
G01X615750Y463000D02*
X613000D01*
G01X625100Y510252D02*
Y510074D01*
G01D02*
Y504200D01*
X625900Y503400D01*
X642940D01*
X643640Y504100D01*
X646350D01*
G01X632628Y558077D02*
Y561428D01*
X632800Y561600D01*
G01X620160Y544793D02*
X620804Y544149D01*
X624207D01*
G01X613900Y555400D02*
X610200D01*
G01X635970Y557600D02*
Y557293D01*
X635344D01*
X632628Y554577D01*
G01X639450Y553700D02*
X639350Y553800D01*
Y557500D01*
G01X632628Y554577D02*
X630707Y552656D01*
Y546590D01*
X630113Y545996D01*
Y544149D01*
G01X639350Y557500D02*
X636070D01*
X635970Y557600D01*
G01X642660Y568043D02*
X638660D01*
G01X642660Y562043D02*
X645379D01*
X647359Y560063D01*
G01D02*
X644796Y557500D01*
X642850D01*
G01X642950Y553700D02*
X642910Y553660D01*
Y549543D01*
G01X642850Y557500D02*
X642950Y557400D01*
Y553700D01*
G01X621104Y539027D02*
X614273D01*
X612500Y540800D01*
G01D02*
X607676D01*
G01X603164Y540753D02*
X607629D01*
X607676Y540800D01*
G01X625398Y550500D02*
Y554931D01*
X625410Y554943D01*
G01X626176Y544099D02*
Y547789D01*
X625398Y548567D01*
Y550500D01*
G01X639410Y549543D02*
X638440Y550513D01*
X634384D01*
G01X633266Y540996D02*
Y549395D01*
X634384Y550513D01*
G01X628144Y544099D02*
Y559527D01*
X628160Y559543D01*
G01X623327Y559229D02*
X625298D01*
X625612Y559543D01*
X628160D01*
G01X623542Y563702D02*
X623327Y563487D01*
Y559229D01*
G01X616160Y542700D02*
Y542043D01*
X617207Y540996D01*
X621054D01*
G01X614000Y561250D02*
X616900D01*
X619400Y563750D01*
G01X623542Y567202D02*
X622852D01*
X619400Y563750D01*
G01X603831Y548331D02*
X606600Y551100D01*
G01X603164Y544253D02*
Y547664D01*
X603831Y548331D01*
G01X722835Y232677D02*
X721260Y234252D01*
G01X732283Y251575D02*
X732284D01*
X733858Y253149D01*
G01X729134Y251575D02*
Y251576D01*
X730710Y253152D01*
G01X732283Y232677D02*
X733859Y234253D01*
G01X732283Y235827D02*
X733859Y237403D01*
G01X732283Y242126D02*
X732284D01*
X733858Y243700D01*
G01X732283Y245275D02*
X732284D01*
X733858Y246849D01*
G01X732283Y248425D02*
X732284D01*
X733858Y249999D01*
G01X732283Y264173D02*
X732284D01*
X733858Y265747D01*
G01X722835Y220079D02*
Y220111D01*
X721295Y221651D01*
G01X722835Y251575D02*
X721260Y253150D01*
G01X722835Y257874D02*
X721260Y259449D01*
G01X722835Y264173D02*
X721260Y265748D01*
G01X698350Y249400D02*
X700336D01*
X701500Y250564D01*
G01X725984Y235827D02*
X727559Y234252D01*
G01X729134Y229527D02*
Y229490D01*
X727594Y227950D01*
G01X729134Y226378D02*
Y226410D01*
X727594Y227950D01*
G01X732283Y229527D02*
X735433D01*
G01X722835Y226378D02*
Y226377D01*
X725984Y223228D01*
G01X732283Y238976D02*
X733859Y240552D01*
G01X725984Y242126D02*
X727559Y240551D01*
G01X725984Y248425D02*
X725986D01*
X727560Y246851D01*
G01X725984Y254724D02*
X725985D01*
X727559Y253150D01*
G01X722835Y245275D02*
Y245277D01*
X721261Y246851D01*
G01X719685Y245275D02*
X721261Y246851D01*
G01X725984Y261023D02*
X725985D01*
X727559Y259449D01*
G01X725984Y245275D02*
X727560Y246851D01*
G01X716535Y245275D02*
Y245238D01*
X718089Y243684D01*
G01X713386Y245275D02*
X713848D01*
X714173Y245600D01*
X715749D01*
X716074Y245275D01*
X716535D01*
G01X719685Y242126D02*
X719647D01*
X718089Y243684D01*
G01X719685Y245275D02*
X719680D01*
X718089Y243684D01*
G01X732283Y226378D02*
X729134D01*
G01X732283Y223228D02*
Y226378D01*
G01X729134Y232677D02*
Y232678D01*
X730710Y234254D01*
G01X729134Y235827D02*
X730710Y237403D01*
G01X729134Y238976D02*
Y238977D01*
X730710Y240553D01*
G01X729134Y242126D02*
X730710Y243702D01*
G01X729134Y245275D02*
Y245276D01*
X730710Y246852D01*
G01X729134Y248425D02*
Y248426D01*
X730710Y250002D01*
G01X729134Y264173D02*
Y264174D01*
X730710Y265750D01*
G01X733858Y256299D02*
X732283Y254724D01*
G01X729134D02*
Y254726D01*
X730710Y256302D01*
G01X729134Y257874D02*
X729138D01*
X730710Y256302D01*
G01X732283Y257874D02*
X733858Y256299D01*
G01X729134Y261023D02*
Y264173D01*
G01X732283Y261023D02*
Y264173D01*
G01X725984Y229527D02*
Y229528D01*
X722835Y232677D01*
G01Y238976D02*
Y238977D01*
X721261Y240551D01*
G01X725984Y223228D02*
X725985D01*
X727559Y221654D01*
G01D02*
X729134Y220079D01*
G01X722835Y283071D02*
X724410Y281496D01*
G01X729134Y283071D02*
X729135D01*
X730710Y281496D01*
G01X732283Y283071D02*
X732284D01*
X733859Y281496D01*
G01X732283Y273622D02*
X733859Y275198D01*
G01X729134Y270472D02*
X730710Y272048D01*
G01X732283Y267323D02*
X732284D01*
X733858Y268897D01*
G01X725984Y267323D02*
X727559Y265748D01*
G01X729134Y273622D02*
X727559Y272047D01*
G01X729134Y276771D02*
X727559Y278346D01*
G01X729134Y279921D02*
X727559Y278346D01*
G01X732283Y279921D02*
X732284D01*
X733859Y278346D01*
G01X735433Y279921D02*
Y279920D01*
X733859Y278346D01*
G01X722835Y270472D02*
X721260Y272047D01*
G01X722835Y276771D02*
X721260Y275196D01*
G01X725984Y286220D02*
Y286221D01*
X722835Y289370D01*
G01X729134Y286220D02*
Y289370D01*
G01X732283Y286220D02*
X735433Y289370D01*
G01X732283Y276771D02*
X732284D01*
X733859Y278346D01*
G01X725984Y273622D02*
X727559Y272047D01*
G01X710060Y328310D02*
Y328390D01*
X708910Y329540D01*
Y330600D01*
X708100Y331410D01*
G01X729134Y267323D02*
X730710Y268899D01*
G01X725984Y279921D02*
Y279922D01*
X724410Y281496D01*
G01X732283Y270472D02*
X730710Y268899D01*
G01X724410Y284645D02*
X725984Y283071D01*
G01X722835Y286220D02*
X724410Y284645D01*
G01X702824Y464430D02*
X700201D01*
X696527Y460756D01*
G01X690300Y460200D02*
X690856Y460756D01*
X696527D01*
G01X730600Y493100D02*
X734934Y488766D01*
X736932D01*
G01X716078Y492334D02*
Y493008D01*
X717070Y494000D01*
X720200D01*
G01X724900D02*
X720200D01*
G01X724900D02*
X728800Y490100D01*
Y489100D01*
X729365Y488535D01*
G01D02*
X732621Y485279D01*
X735414D01*
G01X702390Y492310D02*
X705150D01*
X710330Y497490D01*
G01X702390Y492310D02*
X698694D01*
X696100Y489716D01*
G01X699450Y504000D02*
Y503236D01*
X696100Y499886D01*
Y499100D01*
G01D02*
Y489716D01*
G01X702515Y597064D02*
Y587242D01*
G01X708420D02*
Y589637D01*
X711081Y592298D01*
Y595223D01*
G01X723676Y591179D02*
Y596194D01*
X726600Y599118D01*
Y607300D01*
X727872Y608572D01*
Y616709D01*
X723415Y621166D01*
G01X713575Y556227D02*
Y558540D01*
X711115Y561000D01*
X709569D01*
X707699Y562870D01*
Y564001D01*
X706452Y565248D01*
Y567956D01*
G01X713575Y556227D02*
X713849Y555953D01*
X718551D01*
G01D02*
Y558077D01*
X720150Y559676D01*
Y560600D01*
G01X706588Y553602D02*
Y552512D01*
X710000Y549100D01*
G01X714800Y567956D02*
X710389D01*
G01X718550Y569100D02*
X717406Y567956D01*
X714800D01*
G01X710100Y545600D02*
X707800D01*
X706600Y546800D01*
G01X702515Y567956D02*
Y561310D01*
X703200Y560625D01*
Y558300D01*
G01X703088Y553602D02*
Y552142D01*
X705540Y549690D01*
Y547860D01*
X706600Y546800D01*
G01X703200Y558300D02*
X703088Y558188D01*
Y553602D01*
G01X708420Y567956D02*
Y565685D01*
X710144Y563961D01*
X711945D01*
X714777Y561129D01*
G01D02*
X716679D01*
X720150Y564600D01*
G01X705176Y593429D02*
X704483Y592736D01*
Y587242D01*
G01X710389D02*
X717314D01*
G01X727676Y587679D02*
X723676D01*
G01X731676D02*
X727676D01*
G01X717314Y587242D02*
X720152D01*
X720589Y587679D01*
X723676D01*
G01X731676D02*
Y585597D01*
X729779Y583700D01*
X728000D01*
G01X727676Y591179D02*
X731676D01*
G01X736394Y593579D02*
Y592150D01*
X735423Y591179D01*
X731676D01*
G01X717450Y551554D02*
Y549014D01*
X716397Y547961D01*
X714978D01*
G01X707826Y601429D02*
Y592579D01*
X706452Y591205D01*
Y587242D01*
G01X713575Y552727D02*
Y549364D01*
X714978Y547961D01*
G01X705676Y562429D02*
X705015Y563090D01*
Y563137D01*
X704483Y563669D01*
Y567956D01*
G01X708000Y619000D02*
X707000Y618000D01*
X681400D01*
X679800Y619600D01*
Y634661D01*
G01X733872Y629500D02*
Y604425D01*
X731076Y601629D01*
G01X716300Y603700D02*
X716126Y603526D01*
Y598329D01*
G01X716345Y608340D02*
Y603745D01*
X716300Y603700D01*
G01X716126Y598329D02*
Y594029D01*
G01D02*
X714758D01*
X713564Y595223D01*
X711081D01*
G01X707750Y614500D02*
X706550Y615700D01*
X681700D01*
X679800Y613800D01*
Y599739D01*
G01X714000Y619000D02*
X716166Y621166D01*
X723415D01*
G01X711250Y614500D02*
Y616250D01*
X714000Y619000D01*
G01X703800Y604950D02*
Y608400D01*
G01X731076Y595629D02*
X735097D01*
X736394Y594332D01*
Y593579D01*
G01X712708Y603038D02*
X711432D01*
X709823Y601429D01*
X707826D01*
G01X703800Y601450D02*
X707805D01*
X707826Y601429D01*
G01X668500Y709550D02*
Y707700D01*
G01Y710050D02*
Y712500D01*
X669500Y713500D01*
X693372D01*
X733872Y673000D01*
Y629500D01*
G01X788980Y47062D02*
Y37270D01*
X787360Y35650D01*
G01X751500Y54230D02*
Y60240D01*
X752331Y61071D01*
G01X760140Y58080D02*
Y61415D01*
X758424Y63131D01*
X754391D01*
X752331Y61071D01*
G01X751500Y48230D02*
X751850Y47880D01*
Y26339D01*
X753780Y24409D01*
G01X773780D02*
X772755Y25434D01*
Y39735D01*
G01X766542Y44076D02*
X765260Y45358D01*
Y50010D01*
G01X766755Y39735D02*
Y43863D01*
X766542Y44076D01*
G01X807006Y50692D02*
X799692D01*
X797500Y48500D01*
G01D02*
X795024Y46024D01*
Y42000D01*
G01X765900Y191900D02*
Y196747D01*
X765800Y196847D01*
G01X766929Y210630D02*
Y205143D01*
X765800Y204014D01*
Y196847D01*
G01X768579Y203964D02*
Y209990D01*
X768561Y210008D01*
G01X768505Y243702D02*
X766931Y242128D01*
Y242126D01*
X766929D01*
G01X785827Y245275D02*
Y245263D01*
X784277Y243713D01*
G01X785827Y229527D02*
X784253Y227953D01*
G01X785827Y232677D02*
X784253Y231103D01*
G01X751181Y235827D02*
X751182D01*
X752756Y234253D01*
G01X751181Y232677D02*
X751182D01*
X752756Y231103D01*
G01X751181Y226378D02*
X751182D01*
X752756Y224804D01*
G01X751181Y229527D02*
X751183D01*
X752756Y227954D01*
G01X748031Y232677D02*
X748032D01*
X749606Y231103D01*
G01X748031Y235827D02*
X748032D01*
X749606Y234253D01*
G01X748031Y229527D02*
X748033D01*
X749606Y227954D01*
G01X748031Y226378D02*
X748032D01*
X749606Y224804D01*
G01X741732Y254724D02*
X741078Y255378D01*
Y255379D01*
X740158Y256299D01*
G01X738583Y251575D02*
X738584D01*
X740158Y253149D01*
G01X735433Y251575D02*
X735434D01*
X737008Y253149D01*
G01X770079Y238976D02*
X770081D01*
X771655Y237402D01*
G01X770079Y229527D02*
X766929Y232677D01*
G01X763779Y238976D02*
X765353Y237402D01*
G01X735433Y238976D02*
X737009Y237400D01*
G01X735433Y242126D02*
X735434D01*
X737008Y243700D01*
G01X735433Y245275D02*
X735434D01*
X737008Y246849D01*
G01X735433Y248425D02*
X735434D01*
X737008Y249999D01*
G01X735433Y264173D02*
X735434D01*
X737008Y265747D01*
G01X738583Y245275D02*
X738584D01*
X740158Y246849D01*
G01X738583Y264173D02*
X738584D01*
X740158Y265747D01*
G01X741732Y248425D02*
X740158Y249999D01*
G01X795275Y223228D02*
X795736D01*
X796062Y223554D01*
X797638D01*
X797964Y223228D01*
X798425D01*
G01X776378Y229527D02*
X776380D01*
X777954Y227953D01*
G01X776378Y232677D02*
X776380D01*
X777954Y231103D01*
G01X792126Y220079D02*
X793701Y221654D01*
G01X798425Y267323D02*
Y264173D01*
G01X796822Y256289D02*
X796698Y256165D01*
Y256147D01*
X795275Y254724D01*
G01X798425Y264173D02*
X798407D01*
X796822Y262588D01*
G01X798425Y261023D02*
Y261041D01*
X799972Y262588D01*
G01X798425Y251575D02*
X799991Y250009D01*
Y249972D01*
G01X796822Y262588D02*
X795275Y261041D01*
Y261023D01*
G01X763779Y235827D02*
X763781D01*
X765355Y234253D01*
G01X763779Y232677D02*
X765354Y231102D01*
G01X763779Y229527D02*
X763781D01*
X765355Y227953D01*
G01X763779Y226378D02*
X763781D01*
X765355Y224804D01*
G01X754331Y232677D02*
X754332D01*
X755906Y231103D01*
G01X754331Y229527D02*
X754333D01*
X755906Y227954D01*
G01X763779Y223228D02*
X763780D01*
X765354Y221654D01*
G01X757480Y235827D02*
X755906Y234253D01*
G01X760630Y232677D02*
X763779D01*
G01X760630Y229527D02*
X763779D01*
G01X760630Y226378D02*
X763779D01*
G01X744882Y232677D02*
X744883D01*
X746457Y231103D01*
G01X744882Y229527D02*
X744884D01*
X746457Y227954D01*
G01X773228Y220079D02*
X774804Y221655D01*
G01X773228Y223228D02*
X774804Y224804D01*
G01X773228Y226378D02*
X774804Y227954D01*
G01X776378Y223228D02*
X776377D01*
X774804Y221655D01*
G01X770079Y220079D02*
X773228D01*
G01X770079Y223228D02*
X773228D01*
G01X770079Y226378D02*
X773228D01*
G01X763779Y216929D02*
X762205Y215355D01*
G01X760630Y216929D02*
X760631D01*
X762205Y215355D01*
G01X763779Y213779D02*
X762205Y212205D01*
G01X760630Y213779D02*
X760631D01*
X762205Y212205D01*
G01X760630Y210630D02*
X762205Y212205D01*
G01X773228Y216929D02*
X771654Y215355D01*
G01X773228Y213779D02*
X771654Y212205D01*
G01X773228Y210630D02*
X771654Y209056D01*
G01X738583Y232677D02*
X737009Y231103D01*
G01X735433Y232677D02*
X735435D01*
X737009Y231103D01*
G01X738583Y229527D02*
X737009Y227953D01*
G01X735433Y229527D02*
X735435D01*
X737009Y227953D01*
G01X766929Y223228D02*
X766928D01*
X765354Y221654D01*
G01X757480Y229527D02*
X757479D01*
X755906Y227954D01*
G01X757480Y226378D02*
X755906Y224804D01*
G01X754331Y226378D02*
X754332D01*
X755906Y224804D01*
G01X744882Y226378D02*
X744883D01*
X746457Y224804D01*
G01X744882Y238976D02*
Y238977D01*
X746457Y240552D01*
G01X751181Y238976D02*
X752757Y240552D01*
G01X754331Y238976D02*
Y238978D01*
X752757Y240552D01*
G01X760630Y238976D02*
Y238978D01*
X759056Y240552D01*
G01X788976Y264173D02*
X788988D01*
X790538Y265723D01*
G01X792126Y261023D02*
X792088D01*
X790551Y259486D01*
G01X788976Y261023D02*
X789014D01*
X790551Y259486D01*
G01X792126Y257874D02*
Y257911D01*
X790551Y259486D01*
G01X782677Y248425D02*
X782715D01*
X784277Y246863D01*
G01X779527Y238976D02*
X779529D01*
X781103Y237402D01*
G01X782677Y232677D02*
X781103Y231103D01*
G01X779527Y232677D02*
X779529D01*
X781103Y231103D01*
G01X782677Y229527D02*
X782676D01*
X781103Y227954D01*
G01X779527Y229527D02*
X779530D01*
X781103Y227954D01*
G01X795275Y223228D02*
X793701Y221654D01*
G01X766929Y220079D02*
X765354Y221654D01*
G01X763779Y220079D02*
X765354Y221654D01*
G01X779527Y261023D02*
Y261012D01*
X777976Y259461D01*
G01X776378Y257874D02*
X776389D01*
X777976Y259461D01*
G01X770079Y257874D02*
X771654Y259449D01*
G01X773228Y261023D02*
X771654Y259449D01*
G01X773228Y257874D02*
Y257875D01*
X771654Y259449D01*
G01X776378Y264173D02*
X776388D01*
X777976Y265761D01*
G01X773228Y229527D02*
X773231D01*
X774804Y227954D01*
G01X770079Y229527D02*
X773228D01*
G01Y232677D02*
X776378D01*
G01X770079Y226378D02*
X766929D01*
G01X735433Y235827D02*
X735435D01*
X737009Y234253D01*
G01X776378Y238976D02*
X776380D01*
X777954Y237402D01*
G01X757480Y232677D02*
X755906Y231103D01*
G01X754331Y235827D02*
X754332D01*
X755906Y234253D01*
G01X760630Y235827D02*
X763779D01*
G01X744882D02*
X744883D01*
X746457Y234253D01*
G01X782677Y261023D02*
Y261016D01*
X784267Y259426D01*
G01X785827Y261023D02*
Y260986D01*
X784267Y259426D01*
G01X785827Y257874D02*
X785819D01*
X784267Y259426D01*
G01X782677Y257874D02*
X782715D01*
X784267Y259426D01*
G01X773228Y251575D02*
Y251576D01*
X771654Y253150D01*
G01X782677Y251575D02*
X782690D01*
X784277Y253162D01*
G01X779527Y251575D02*
X782677D01*
G01X776378D02*
X779527D01*
G01X782677Y254724D02*
X782715D01*
X784267Y256276D01*
G01X779527Y254724D02*
X782677D01*
G01X779527D02*
X779065D01*
X778741Y254400D01*
X777165D01*
X776841Y254724D01*
X776378D01*
G01X785827D02*
X785819D01*
X784267Y256276D01*
G01X785827Y251575D02*
Y251612D01*
X784277Y253162D01*
G01X782677Y264173D02*
X785827Y267323D01*
G01X788976Y264173D02*
Y261023D01*
G01X735433Y226378D02*
X735434D01*
X737009Y227953D01*
G01X738583Y223228D02*
X738582D01*
X737008Y221654D01*
G01X738583Y226378D02*
Y223228D01*
G01X773228Y248425D02*
Y251575D01*
G01X776378Y248425D02*
X779527D01*
G01D02*
X779865Y248763D01*
X782339D01*
X782677Y248425D01*
G01X779527Y242126D02*
Y238976D01*
G01X776378Y242126D02*
X779527D01*
G01X776378D02*
X773228D01*
G01X776378Y245275D02*
Y248425D01*
G01X798425Y238976D02*
X798424D01*
X795275Y235827D01*
G01Y242126D02*
X795255D01*
X793672Y243709D01*
G01X792126Y226378D02*
Y226377D01*
X795275Y223228D01*
G01X792126Y216929D02*
Y220079D01*
G01X802227Y208424D02*
X801991Y208660D01*
X796710D01*
X795275Y210095D01*
Y210630D01*
G01X744882Y264173D02*
Y264210D01*
X746433Y265761D01*
G01X751181Y264173D02*
X752757Y265749D01*
G01X757480Y264173D02*
X759056Y265749D01*
G01X763779Y264173D02*
X765355Y265749D01*
G01X770079Y264173D02*
Y264174D01*
X771654Y265749D01*
G01X760630Y261023D02*
X760593D01*
X759031Y259461D01*
G01X757480Y257874D02*
Y257910D01*
X759031Y259461D01*
G01X754331Y261023D02*
X752757Y259449D01*
G01X751181Y257874D02*
X751182D01*
X752757Y259449D01*
G01X748031Y261023D02*
X746457Y259449D01*
G01D02*
X744882Y257874D01*
G01Y251575D02*
X746421Y253114D01*
Y253149D01*
G01X740122Y243700D02*
X741696Y242126D01*
X741732D01*
G01X738583Y248425D02*
X738584D01*
X740158Y249999D01*
G01X738583Y238976D02*
X740132Y240525D01*
Y240562D01*
G01X773228Y238976D02*
Y238975D01*
X771655Y237402D01*
G01X766929Y235827D02*
X765355Y234253D01*
G01X770079Y232677D02*
X766929Y235827D01*
G01Y232677D02*
X765354Y231102D01*
G01X740158Y256299D02*
X738583Y254724D01*
G01X737008Y256299D02*
X735433Y254724D01*
G01Y257874D02*
X737008Y256299D01*
G01X738583Y257874D02*
X740158Y256299D01*
G01X735433Y261023D02*
Y264173D01*
G01X738583Y261023D02*
Y264173D01*
G01Y235827D02*
X737009Y234253D01*
G01X741732Y235827D02*
X744882D01*
G01X741732Y232677D02*
X744882D01*
G01X741732Y229527D02*
X744882D01*
G01X741732Y226378D02*
X744882D01*
G01X748031Y238976D02*
Y238978D01*
X746457Y240552D01*
G01X757480Y238976D02*
X759056Y240552D01*
G01X741732Y261023D02*
X744882Y264173D01*
G01X766929Y229527D02*
X765355Y227953D01*
G01X766929Y226378D02*
X765355Y224804D01*
G01X782677Y245275D02*
X782715D01*
X784277Y243713D01*
G01X773228Y235827D02*
Y235829D01*
X771655Y237402D01*
G01X776378Y235827D02*
X776379D01*
X777954Y237402D01*
G01X782677Y235827D02*
Y235828D01*
X781103Y237402D01*
G01X779527Y235827D02*
Y235829D01*
X777954Y237402D01*
G01X785827Y235827D02*
Y232677D01*
G01X782677Y238976D02*
X781103Y237402D01*
G01X785827Y242126D02*
Y242163D01*
X784277Y243713D01*
G01X782677Y242126D02*
X782690D01*
X784277Y243713D01*
G01X785827Y248425D02*
Y248413D01*
X784277Y246863D01*
G01X785827Y238976D02*
Y235827D01*
G01X795275Y248425D02*
X795047Y248197D01*
X794872Y248177D01*
X793440Y246745D01*
Y246589D01*
X792126Y245275D01*
G01X766929Y261023D02*
X765355Y259449D01*
G01X763779Y257874D02*
X765354Y259449D01*
X765355D01*
G01X770079Y251575D02*
X771654Y253150D01*
G01D02*
X773228Y254724D01*
G01X765355Y253150D02*
X766929Y254724D01*
G01X763779Y251575D02*
X763780D01*
X765355Y253150D01*
G01X759056D02*
X760630Y254724D01*
G01X757480Y251575D02*
X757481D01*
X759056Y253150D01*
G01X754331Y254724D02*
X754295D01*
X752720Y253149D01*
G01X751181Y251575D02*
Y251610D01*
X752720Y253149D01*
G01X748031Y254724D02*
X746456Y253149D01*
X746421D01*
G01X748031Y248425D02*
X746457Y246851D01*
Y246850D01*
G01D02*
X744882Y245275D01*
G01X752757Y246851D02*
X754331Y248425D01*
G01X751181Y245275D02*
X752757Y246851D01*
G01X759056D02*
X760630Y248425D01*
G01X757480Y245275D02*
X759056Y246851D01*
G01X766929Y248425D02*
X765354Y246850D01*
G01D02*
X763779Y245275D01*
G01X760630Y242126D02*
X759056Y240552D01*
G01X754331Y242126D02*
X752757Y240552D01*
G01X748031Y242126D02*
X746457Y240552D01*
G01X782677Y223228D02*
X781103Y221654D01*
X781102D01*
G01D02*
X779527Y220079D01*
G01X752756Y221654D02*
X754331Y220079D01*
G01X757480Y223228D02*
X759054Y221654D01*
X759055D01*
G01D02*
X760630Y220079D01*
G01X751181Y223228D02*
X751180D01*
X749606Y221654D01*
G01D02*
X748031Y220079D01*
G01X744882Y223228D02*
X743308Y221654D01*
X743307D01*
G01X741732Y220079D02*
X743307Y221654D01*
G01X735433Y220079D02*
X737008Y221654D01*
G01X792126Y245275D02*
Y245255D01*
X793672Y243709D01*
G01X792126Y238976D02*
X793700Y237402D01*
X793701D01*
G01X795275Y235827D02*
X793701Y237401D01*
Y237402D01*
G01X792126Y232677D02*
X793700Y231103D01*
X793701D01*
G01X795275Y229527D02*
X793701Y231101D01*
Y231103D01*
G01X788976Y223228D02*
X787402Y221654D01*
G01D02*
X785827Y220079D01*
G01X788976Y213779D02*
X787401Y215354D01*
G01X770079Y242126D02*
Y242128D01*
X768505Y243702D01*
G01X770079Y245275D02*
X770078D01*
X768505Y243702D01*
G01X763779Y242126D02*
Y242088D01*
X762217Y240526D01*
G01X766929Y238976D02*
Y238978D01*
X765355Y240552D01*
G01X770079Y235827D02*
X770078D01*
X766929Y238976D01*
G01X795275Y232677D02*
Y232680D01*
X793701Y234254D01*
G01X768504Y215355D02*
X770078Y216929D01*
X770079D01*
G01X754331Y279921D02*
X752756Y278346D01*
G01X760630Y286220D02*
Y286253D01*
X759073Y287810D01*
G01X735433Y283071D02*
X735434D01*
X737009Y281496D01*
G01X740159Y278345D02*
X738584Y279920D01*
Y279921D01*
X738583D01*
G01X757480Y273622D02*
Y273658D01*
X759031Y275209D01*
G01X766929Y273622D02*
Y273621D01*
X765356Y272048D01*
G01X766929Y276771D02*
Y276770D01*
X765356Y275197D01*
G01X766929Y279921D02*
Y279920D01*
X765356Y278347D01*
G01X738583Y270472D02*
X738584D01*
X740158Y272046D01*
G01X735433Y270472D02*
X735434D01*
X737008Y272046D01*
G01X735433Y267323D02*
X735434D01*
X737008Y268897D01*
G01X741732Y267323D02*
X740158Y268897D01*
G01X744882Y270472D02*
X746457Y272047D01*
G01X760630Y270472D02*
Y270509D01*
X762181Y272060D01*
G01X757480Y270472D02*
Y270509D01*
X759031Y272060D01*
G01X760630Y276771D02*
X760632D01*
X762206Y275197D01*
G01X788976Y295669D02*
X788995D01*
X789684Y294980D01*
Y293566D01*
X788976Y292858D01*
Y292519D01*
G01Y289370D02*
X788975D01*
X787400Y287795D01*
G01X792126Y289370D02*
X792125D01*
X790550Y287795D01*
G01X798425Y295669D02*
X801575Y298819D01*
G01X770079Y283071D02*
Y283064D01*
X768489Y281474D01*
G01X766929Y279921D02*
X766936D01*
X768489Y281474D01*
G01X763779Y283071D02*
X763746D01*
X762189Y281514D01*
G01X779527Y289370D02*
X779530D01*
X781100Y287800D01*
G01X779527Y286220D02*
Y286227D01*
X781100Y287800D01*
G01X770079Y289370D02*
X768503Y287794D01*
G01X776378Y283071D02*
Y283033D01*
X777915Y281496D01*
G01X776378Y279921D02*
Y279959D01*
X777915Y281496D01*
G01X782677Y283071D02*
Y283108D01*
X784221Y284652D01*
G01X785827Y286220D02*
X785789D01*
X784221Y284652D01*
G01X788976Y286220D02*
Y286221D01*
X790550Y287795D01*
G01X788976Y283071D02*
X790551Y284646D01*
G01X788976Y276771D02*
Y276797D01*
X787419Y278354D01*
G01X785827Y279921D02*
X785852D01*
X787419Y278354D01*
G01X782677Y279921D02*
Y279884D01*
X784243Y278318D01*
G01X782677Y276771D02*
X782696D01*
X784243Y278318D01*
G01X779527Y279921D02*
X777953Y278347D01*
G01X779527Y276771D02*
Y276773D01*
X777953Y278347D01*
G01X770079Y279921D02*
X770042D01*
X768489Y281474D01*
G01X776378Y276771D02*
X776380D01*
X777953Y275198D01*
G01X779527Y273622D02*
Y273624D01*
X777953Y275198D01*
G01X785827Y273622D02*
Y273584D01*
X784290Y272047D01*
G01X788976Y273622D02*
Y273596D01*
X790519Y272053D01*
G01X792126Y270472D02*
X792100D01*
X790519Y272053D01*
G01X776378Y273622D02*
X776341D01*
X774789Y275174D01*
G01X773228Y276771D02*
Y276735D01*
X774789Y275174D01*
G01X788976Y267323D02*
Y267285D01*
X790538Y265723D01*
G01X748031Y279921D02*
X749606Y278346D01*
G01X751181Y279921D02*
X749606Y278346D01*
G01X776378Y267323D02*
X776414D01*
X777976Y265761D01*
G01X779527Y267323D02*
Y267312D01*
X777976Y265761D01*
G01X773228Y273622D02*
X773237D01*
X774789Y275174D01*
G01X779527Y270472D02*
Y270510D01*
X781064Y272047D01*
G01X776378Y270472D02*
X779527D01*
G01X782677Y273622D02*
X782715D01*
X784290Y272047D01*
G01X782677Y270472D02*
X782715D01*
X784290Y272047D01*
G01X785827Y267323D02*
X788976D01*
G01X782677D02*
X782352Y267648D01*
Y270147D01*
X782677Y270472D01*
G01X788976Y267323D02*
X788977D01*
X792126Y270472D01*
G01Y279921D02*
X788976Y283071D01*
G01X760630Y279921D02*
X760632D01*
X762206Y278347D01*
G01X763779Y279921D02*
Y279920D01*
X762206Y278347D01*
G01X763779Y276771D02*
Y276770D01*
X762206Y275197D01*
G01X748031Y267323D02*
X747995D01*
X746433Y265761D01*
G01X752757Y265749D02*
X754331Y267323D01*
G01X759056Y265749D02*
X760630Y267323D01*
G01X765355Y265749D02*
X766929Y267323D01*
G01X771654Y265749D02*
X773228Y267323D01*
G01X752731Y272060D02*
Y272022D01*
X751181Y270472D01*
G01X760630Y273622D02*
Y273611D01*
X762181Y272060D01*
G01X738583Y267323D02*
X738584D01*
X740158Y268897D01*
G01X770079Y276771D02*
X766929D01*
G01X770079Y273622D02*
X766929D01*
G01X751181D02*
X751182D01*
X752757Y275197D01*
G01X748031Y273622D02*
X748032D01*
X749607Y275197D01*
G01X744882Y273622D02*
X746457Y275197D01*
G01X738583Y273622D02*
X740158Y275197D01*
G01X738583Y276771D02*
Y276770D01*
X737009Y275196D01*
G01X738583Y283071D02*
X738584D01*
X740159Y281496D01*
G01X735433Y276771D02*
X735434D01*
X737009Y275196D01*
G01X744882Y276771D02*
X744883D01*
X746457Y275197D01*
G01X748031Y276771D02*
X748033D01*
X749607Y275197D01*
G01X751181Y276771D02*
X751183D01*
X752757Y275197D01*
G01X757480Y276771D02*
Y276760D01*
X759031Y275209D01*
G01X763779Y273622D02*
Y273624D01*
X762206Y275197D01*
G01X763779Y270472D02*
X763780D01*
X765356Y272048D01*
G01X766929Y270472D02*
Y270475D01*
X765356Y272048D01*
G01X773228Y270472D02*
X773264D01*
X774826Y268910D01*
G01X770079Y270472D02*
X773228D01*
G01X770079Y267323D02*
X770080D01*
X771654Y265749D01*
G01X741732Y273622D02*
Y273620D01*
X740158Y272046D01*
G01X741732Y276771D02*
X740158Y275197D01*
G01X741732Y279921D02*
Y279923D01*
X740159Y281496D01*
G01X741732Y283071D02*
Y283069D01*
X740159Y281496D01*
G01X744882Y279921D02*
Y276771D01*
G01X748031Y283071D02*
Y283108D01*
X749593Y284670D01*
G01X744882Y283071D02*
X745344D01*
X745669Y282746D01*
X747245D01*
X747570Y283071D01*
X748031D01*
G01X754331Y276771D02*
X752757Y275197D01*
G01X754331Y273622D02*
X754756D01*
X755094Y273960D01*
X756670D01*
X757008Y273622D01*
X757480D01*
G01Y279921D02*
X757975D01*
X758282Y279614D01*
X759858D01*
X760165Y279921D01*
X760630D01*
G01Y289370D02*
Y289368D01*
X762204Y287794D01*
G01X757480Y283071D02*
X757481D01*
X760630Y286220D01*
G01X751181D02*
Y289370D01*
G01Y283071D02*
Y283082D01*
X749593Y284670D01*
G01X754331Y283071D02*
Y279921D01*
G01Y286220D02*
Y283071D01*
G01X760630Y289370D02*
X760666D01*
X762229Y290933D01*
G01X760630Y292519D02*
Y292546D01*
X762173Y294089D01*
G01X763779Y295669D02*
X763753D01*
X762173Y294089D01*
G01X766929Y295669D02*
X766468Y296130D01*
X764240D01*
X763779Y295669D01*
G01X795275Y289370D02*
X796839Y290934D01*
G01X784252Y268885D02*
X785827Y270460D01*
Y270472D01*
G01X757480Y286220D02*
Y286222D01*
X755898Y287804D01*
G01X741732Y270472D02*
Y270509D01*
X743283Y272060D01*
G01X754331Y270472D02*
Y270509D01*
X755882Y272060D01*
G01X753099Y523016D02*
X752999Y522916D01*
X748899D01*
G01X757099Y523016D02*
X753099D01*
G01X744018Y516886D02*
X734300Y507168D01*
Y495184D01*
X738901Y490583D01*
Y488766D01*
G01X744018Y516886D02*
Y518035D01*
X748899Y522916D01*
G01X742300Y498200D02*
Y497800D01*
X741600Y497100D01*
Y493100D01*
X742838Y491862D01*
Y488766D01*
G01X750712D02*
X752166D01*
X753258Y489858D01*
Y495558D01*
X754462Y496762D01*
G01X759200Y500750D02*
X755300D01*
G01D02*
Y497600D01*
X754462Y496762D01*
G01X762500Y483800D02*
X759900D01*
X759000Y482900D01*
G01D02*
X756600D01*
X755042Y481342D01*
X752230D01*
G01X750600Y497400D02*
Y493284D01*
X748743Y491427D01*
Y488766D01*
G01X751400Y500750D02*
X750758Y500108D01*
Y497558D01*
X750600Y497400D01*
G01X763147Y496377D02*
X760206D01*
X759169Y497414D01*
G01X763801Y492269D02*
X763147Y492923D01*
Y496377D01*
G01X767247Y496627D02*
X767373D01*
X771200Y492800D01*
G01X771069Y488799D02*
Y492669D01*
X771200Y492800D01*
G01X747250Y508600D02*
Y509650D01*
X750000Y512400D01*
X760100D01*
X761200Y511300D01*
G01X767247Y502627D02*
X774823D01*
X777200Y500250D01*
G01X763147Y499877D02*
X765897Y502627D01*
X767247D01*
G01X747500Y504450D02*
Y508350D01*
X747250Y508600D01*
G01X761200Y511300D02*
X762400Y510100D01*
Y500624D01*
X763147Y499877D01*
G01X739900Y505700D02*
Y501450D01*
X740050Y501300D01*
G01X743750Y508600D02*
X742800D01*
X739900Y505700D01*
G01X763801Y488769D02*
X767501D01*
X767569Y488799D01*
G01D02*
X769669Y486699D01*
X774649D01*
X777000Y489050D01*
G01X758901Y488563D02*
X759063D01*
X759269Y488769D01*
X763801D01*
G01X752230Y485279D02*
X755617D01*
X758901Y488563D01*
G01X747500Y500950D02*
X747900Y500550D01*
Y493209D01*
X746775Y492084D01*
Y488766D01*
G01X751400Y504250D02*
X751050D01*
X747750Y500950D01*
X747500D01*
G01X751400Y504250D02*
Y506900D01*
X752569Y508069D01*
X753519D01*
G01D02*
X754331D01*
X755300Y507100D01*
Y504250D01*
G01X743550Y501300D02*
X747150D01*
X747500Y500950D01*
G01X795922Y522858D02*
Y518640D01*
G01D02*
X797406Y517156D01*
X800388D01*
G01X788734Y505600D02*
X790595D01*
X793657Y508662D01*
X794088D01*
G01D02*
X797838D01*
X800471Y506029D01*
Y504968D01*
G01X788734Y505600D02*
X788570Y505764D01*
Y509900D01*
X790200Y511530D01*
Y514000D01*
G01X786004Y514350D02*
X789850D01*
X790200Y514000D01*
G01X800471Y494732D02*
X798332D01*
X796700Y493100D01*
X794000D01*
X793700Y493400D01*
G01D02*
Y496850D01*
X794500Y497650D01*
G01X748899Y526416D02*
Y532203D01*
X754775Y538079D01*
G01X782504Y514350D02*
X781700Y513546D01*
Y510900D01*
G01X780750Y518500D02*
Y516104D01*
X782504Y514350D01*
G01X784500Y518694D02*
X786584Y520778D01*
Y525000D01*
G01X780750Y518500D02*
X784306D01*
X784500Y518694D01*
G01X777200Y496750D02*
X780750D01*
G01X777000Y492550D02*
X781050D01*
G01X754775Y538079D02*
X761055Y544359D01*
X796641D01*
X808400Y532600D01*
Y522978D01*
X805249Y519827D01*
G01X801024Y24409D02*
Y42000D01*
G01X815076Y55812D02*
X816688D01*
X824200Y48300D01*
G01X827024Y42000D02*
Y45476D01*
X824200Y48300D01*
G01X821024Y24409D02*
Y42000D01*
G01X799972Y262588D02*
X801537Y261023D01*
X801575D01*
G01X799991Y249972D02*
X801538Y248425D01*
X801575D01*
G01Y213779D02*
X801621D01*
X804600Y210800D01*
G01X808400D02*
X807780Y211420D01*
Y215080D01*
X805931Y216929D01*
X804724D01*
G01X807468Y234464D02*
X805681Y232677D01*
X804724D01*
G01X803300Y303700D02*
X801575Y301975D01*
Y301968D01*
G01X811750Y322500D02*
Y325000D01*
X810300Y326450D01*
G01X812164Y279674D02*
X811774Y280064D01*
X804867D01*
X804724Y279921D01*
G01X809384Y484984D02*
X807655Y486713D01*
Y490107D01*
G01X800388Y517156D02*
X805096Y512448D01*
Y509593D01*
G01X805249Y519827D02*
X807655Y517421D01*
Y509593D01*
G01X883100Y221150D02*
X886300D01*
G01X888551Y230972D02*
Y226649D01*
G01X882871Y239762D02*
Y243771D01*
G01X892449Y237028D02*
Y241249D01*
G01X886300Y221150D02*
X894450D01*
X897300Y224000D01*
Y239800D01*
X895851Y241249D01*
X892449D01*
G01X882871Y243771D02*
X885393Y241249D01*
X892449D01*
X18700Y54650D03*
X89764Y238386D03*
X90157Y413583D03*
X209189Y37075D03*
Y383483D03*
X201801Y684252D03*
X225601D03*
X309055Y157677D03*
X305906Y182874D03*
Y388386D03*
X309252Y413583D03*
X488838Y137225D03*
Y164744D03*
X489331Y245605D03*
Y698924D03*
X652756Y180000D03*
X865353Y332598D03*
X901000Y21400D03*
X902500Y676000D03*
G54D148*
G01X43480Y47950D02*
Y29700D01*
X38386Y24606D01*
G01X38780Y48010D02*
X43420D01*
X43480Y47950D01*
G01X30270Y48330D02*
X30530Y48070D01*
X34070D01*
G01D02*
X34130Y48010D01*
X38780D01*
G01X75405Y514027D02*
Y509961D01*
X75373Y509929D01*
G01X75405Y514027D02*
X78155Y516777D01*
Y526000D01*
X79900Y527745D01*
Y544856D01*
X79926Y544882D01*
Y546250D01*
X79900Y546276D01*
Y547099D01*
X79626Y547373D01*
Y549450D01*
X81992Y551816D01*
X83599D01*
X83600Y551817D01*
G01X69778Y514027D02*
Y510172D01*
X69900Y510050D01*
G01X78276Y545566D02*
Y534966D01*
X73222Y529912D01*
Y529085D01*
X73810Y528498D01*
X74638D01*
X76312Y530172D01*
X77140D01*
X77728Y529585D01*
Y528758D01*
X72528Y523558D01*
Y516777D01*
X69778Y514027D01*
G01X72577Y543943D02*
X72578D01*
X74151Y545516D01*
G01X72577Y550242D02*
X74092Y551757D01*
X74498D01*
G01X71002Y539219D02*
X69427Y537644D01*
G01X72577Y540794D02*
X74076Y539295D01*
Y535966D01*
G01X72577Y547093D02*
X72731Y547247D01*
X75095D01*
X75860Y546482D01*
Y542550D01*
X75508Y542198D01*
G01X71002Y542368D02*
X69427Y543943D01*
G01X67852Y539219D02*
X69427Y540794D01*
G01Y547093D02*
X71002Y545518D01*
G01X40756Y543876D02*
X40751Y543881D01*
X36808D01*
G01X71002Y545518D02*
X63507D01*
X62573Y544584D01*
X60344D01*
X59844Y544084D01*
Y541135D01*
X59344Y540635D01*
X58344D01*
X57844Y541135D01*
Y544084D01*
X57344Y544584D01*
X55920D01*
X55415Y544079D01*
Y542104D01*
X54359Y541048D01*
X41339D01*
X40756Y541631D01*
Y543876D01*
G01X69427Y556542D02*
X71002Y558117D01*
G01X69427Y572290D02*
X70866Y573729D01*
X73400D01*
X73891Y574220D01*
X75799D01*
X76988Y573031D01*
Y564909D01*
X77558Y564339D01*
X79698D01*
X80268Y564909D01*
Y587123D01*
X82261Y589116D01*
X95740D01*
X96936Y587920D01*
X106234D01*
X108736Y585418D01*
X138675D01*
X141242Y582851D01*
X141339D01*
X142390Y581800D01*
X154634D01*
X154724Y581890D01*
G01X69427Y565990D02*
X69428D01*
X71002Y564416D01*
Y564396D01*
G01X72577Y578589D02*
X72578D01*
X74152Y580163D01*
G01X69427Y578589D02*
Y579828D01*
X70777Y581178D01*
Y590066D01*
X71277Y590566D01*
X73820D01*
X74320Y591066D01*
Y593066D01*
X73820Y593566D01*
X71277D01*
X70777Y594066D01*
Y596797D01*
X77220Y603240D01*
X81010D01*
X83090Y601160D01*
X93620D01*
X100860Y593920D01*
X110828D01*
X113330Y591418D01*
X142484D01*
X143816Y592750D01*
X145743D01*
X147343Y591150D01*
X152750D01*
X154100Y589800D01*
X156263D01*
X157874Y588189D01*
G01X72577Y575439D02*
X74151Y577013D01*
X74152D01*
G01X72577Y562841D02*
X71002Y561266D01*
G01X69427Y562841D02*
Y562842D01*
X67853Y564416D01*
G01X72577Y559691D02*
Y560746D01*
X75066Y563235D01*
G01X72577Y584888D02*
X72689Y585000D01*
X78260D01*
X78760Y585500D01*
Y591071D01*
X79679Y591990D01*
X88930D01*
X89430Y592490D01*
Y594490D01*
X88930Y594990D01*
X81370D01*
X80870Y595490D01*
Y597490D01*
X81370Y597990D01*
X90331D01*
X96901Y591420D01*
X98179D01*
X98679Y590920D01*
X109585D01*
X112087Y588418D01*
X139918D01*
X142850Y585486D01*
Y585416D01*
X143816Y584450D01*
X143886D01*
X144749Y583587D01*
X154674D01*
X154795Y583466D01*
G02X157361Y582403I0J-3629D01*
G01X157874Y581890D01*
G01X72577Y556542D02*
X71002Y554967D01*
G01X69427Y553392D02*
X68077Y552042D01*
X64158D01*
X62809Y553391D01*
X62772D01*
X58147Y558016D01*
X51105D01*
X50605Y558516D01*
Y559924D01*
X50105Y560424D01*
X49105D01*
X48605Y559924D01*
Y558516D01*
X48105Y558016D01*
X47105D01*
X46605Y558516D01*
Y559924D01*
X46105Y560424D01*
X45105D01*
X44605Y559924D01*
Y558516D01*
X44105Y558016D01*
X43600D01*
X40737Y555153D01*
G01X67853Y554967D02*
X69427Y553393D01*
Y553392D01*
G01X36737Y555153D02*
X40737D01*
G01X72577Y553392D02*
X73864Y554679D01*
X76594D01*
X78276Y552997D01*
Y545566D01*
G01X40756Y538249D02*
Y536211D01*
X41468Y535499D01*
X56210D01*
X57345Y536634D01*
Y537684D01*
X57931Y538270D01*
X58759D01*
X59345Y537684D01*
Y533965D01*
X59931Y533379D01*
X60759D01*
X61345Y533965D01*
Y538481D01*
X62692Y539828D01*
Y543284D01*
X63692Y544284D01*
X65937D01*
X66278Y543943D01*
G01X36708Y538254D02*
X40751D01*
X40756Y538249D01*
G01X67853Y542368D02*
X66278Y543943D01*
G01X69427Y550242D02*
X68188D01*
X66789Y548843D01*
X60909D01*
X59777Y547711D01*
X58009D01*
X57440Y548280D01*
Y552121D01*
X56940Y552621D01*
X55940D01*
X55440Y552121D01*
Y547200D01*
X54940Y546700D01*
X41450D01*
X40550Y547600D01*
Y549500D01*
G01X36550D02*
X40550D01*
G01X69427Y550242D02*
X69428D01*
X71002Y548668D01*
G01X36715Y532638D02*
X40640D01*
X40656Y532622D01*
G01X50050Y529400D02*
X48300Y527650D01*
X42650D01*
X40656Y529644D01*
Y532622D01*
G01X72577Y537644D02*
X64333Y529400D01*
X50050D01*
G01X97600Y54810D02*
Y54860D01*
X93640D01*
G01D02*
X92615Y55885D01*
X89034D01*
G01X85630Y34449D02*
Y53661D01*
X84616Y54675D01*
G01X89034Y55885D02*
X85826D01*
X84616Y54675D01*
G01X116500Y477000D02*
Y462872D01*
X119073Y460299D01*
X125481D01*
G01X101113Y519327D02*
Y515363D01*
X101100Y515350D01*
G01X88325Y547093D02*
X89975Y548743D01*
X95568D01*
X103000Y541311D01*
Y521214D01*
X101113Y519327D01*
G01X81032Y514027D02*
X83800Y516795D01*
Y524700D01*
X81100Y527400D01*
Y546200D01*
X83566Y548666D01*
X86749D01*
X88325Y550242D01*
G01X81032Y514027D02*
Y509952D01*
X81068Y509916D01*
G01X105920Y489668D02*
Y485448D01*
G01X93614Y507352D02*
X102448D01*
X102700Y507100D01*
G01X144500Y489500D02*
X139921Y484921D01*
Y473356D01*
X131864Y465299D01*
X126185D01*
G01X142100Y523350D02*
Y527600D01*
X143500Y529000D01*
G01X86659Y514027D02*
Y510064D01*
X86673Y510050D01*
G01X92000Y513950D02*
X86736D01*
X86659Y514027D01*
G01X92000Y513950D02*
X93790D01*
X95036Y515196D01*
Y526618D01*
X99111Y530693D01*
Y539201D01*
X96293Y542019D01*
X93744D01*
G01X142000Y515550D02*
X140229Y517321D01*
X131021D01*
X128252Y514552D01*
X125788D01*
G01X142100Y519850D02*
X140902Y521048D01*
X135012D01*
G01X93614Y501352D02*
X91552D01*
X88900Y498700D01*
G01X93531Y496391D02*
X91209D01*
X88900Y498700D01*
G01X110220Y489628D02*
Y485448D01*
G01X105920Y493168D02*
X101968D01*
X101800Y493000D01*
G01X105920Y493168D02*
X110180D01*
X110220Y493128D01*
G01X126185Y495299D02*
X125481D01*
G01D02*
X120255D01*
X118084Y493128D01*
X110220D01*
G01X137050Y476346D02*
X135202Y478194D01*
Y487252D01*
X152945Y504995D01*
Y515830D01*
X154262Y517147D01*
Y524346D01*
X156410Y526494D01*
X156474D01*
X159889Y529909D01*
Y530729D01*
X165662Y536502D01*
Y539283D01*
X167323Y540944D01*
Y540945D01*
G01X86750Y542368D02*
X85175Y543943D01*
G01X126337Y554085D02*
X125752Y554670D01*
X112314D01*
X111814Y554170D01*
Y551610D01*
X112314Y551110D01*
X128323D01*
X128823Y551610D01*
Y553276D01*
X130694Y555147D01*
Y555853D01*
X129358Y557190D01*
Y557896D01*
X130067Y558605D01*
X130773D01*
X132109Y557268D01*
X132815D01*
X138557Y563010D01*
X143719D01*
X143737Y562992D01*
X154724D01*
G01X155176Y561260D02*
X149591D01*
X149341Y561010D01*
X141994D01*
X139120Y558136D01*
X138412D01*
X137898Y558650D01*
X137190D01*
X136483Y557943D01*
Y557235D01*
X136997Y556721D01*
Y556013D01*
X136290Y555306D01*
X135582D01*
X135068Y555820D01*
X134360D01*
X133653Y555113D01*
Y554405D01*
X134167Y553891D01*
Y553183D01*
X133460Y552476D01*
X132752D01*
X132238Y552990D01*
X131530D01*
X130823Y552283D01*
Y551575D01*
X131337Y551061D01*
Y550353D01*
X130311Y549327D01*
Y546700D01*
G01X85175Y550242D02*
X84838Y549905D01*
X82415D01*
X81276Y548766D01*
G01X119605Y548705D02*
Y544208D01*
X119105Y543708D01*
X116440D01*
X115940Y543208D01*
Y542208D01*
X116440Y541708D01*
X119105D01*
X119605Y541208D01*
Y539224D01*
X120239Y538590D01*
X121772D01*
X122272Y539090D01*
Y548550D01*
X122772Y549050D01*
X123772D01*
X124272Y548550D01*
Y545860D01*
X124772Y545360D01*
X125772D01*
X126272Y545860D01*
Y548380D01*
X126772Y548880D01*
X127772D01*
X128272Y548380D01*
Y545057D01*
X129149Y544180D01*
X130620D01*
X132311Y545871D01*
Y548498D01*
X141943Y558130D01*
X153920D01*
X154724Y558934D01*
Y559842D01*
G01X88325Y537644D02*
X86751Y539218D01*
X86750D01*
G01X83600Y545518D02*
X85175Y547093D01*
G01X88325Y543943D02*
Y543944D01*
X89899Y545518D01*
G01X154724Y556693D02*
X143501D01*
X140993Y554185D01*
X140827D01*
X134401Y547759D01*
Y545132D01*
X129169Y539900D01*
X125720D01*
X125219Y540401D01*
Y542539D01*
X125880Y543200D01*
X127300D01*
G01X88325Y540794D02*
X89899Y539220D01*
Y539218D01*
G01X157874Y556693D02*
X157217Y556037D01*
G02X154995Y555116I-2222J2220D01*
G01X144753D01*
X141822Y552185D01*
X141656D01*
X136401Y546930D01*
Y544303D01*
X129668Y537570D01*
X125290D01*
X124320Y536600D01*
X122371D01*
X122151Y536380D01*
X114700D01*
X113980Y537100D01*
Y541715D01*
X113480Y542215D01*
X112480D01*
X111980Y541715D01*
Y535700D01*
X111480Y535200D01*
X110480D01*
X109980Y535700D01*
Y543715D01*
X110480Y544215D01*
X113480D01*
X113980Y544715D01*
Y545800D01*
X114480Y546300D01*
X117200D01*
G01X83600Y539219D02*
X85175Y540794D01*
G01X86750Y545518D02*
X88325Y547093D01*
G01X122600Y557480D02*
X107900D01*
X107400Y557980D01*
Y560330D01*
X107900Y560830D01*
X133548D01*
X137728Y565010D01*
X143313D01*
X143757Y564566D01*
X158795D01*
G01X88325Y550242D02*
X89849Y551766D01*
X93990D01*
X94816Y552592D01*
X101960D01*
X102460Y553092D01*
Y556330D01*
X101960Y556830D01*
X97690D01*
X97190Y557330D01*
Y558330D01*
X97690Y558830D01*
X104720D01*
X105220Y559330D01*
Y560330D01*
X104720Y560830D01*
X97000D01*
X96563Y561267D01*
Y566460D01*
X97063Y566960D01*
X98063D01*
X98563Y566460D01*
Y563330D01*
X99063Y562830D01*
X100063D01*
X100563Y563330D01*
Y566460D01*
X101063Y566960D01*
X102063D01*
X102563Y566460D01*
Y563330D01*
X103063Y562830D01*
X132719D01*
X136899Y567010D01*
X145456D01*
X145900Y566566D01*
X154300D01*
X154724Y566142D01*
G01X83600Y551817D02*
X85175Y553392D01*
G01X154995Y567766D02*
X146800D01*
X145556Y569010D01*
X136023D01*
X134352Y567339D01*
Y567292D01*
X131930Y564870D01*
X123021D01*
X122521Y565370D01*
Y567260D01*
X122021Y567760D01*
X121021D01*
X120521Y567260D01*
Y565370D01*
X120021Y564870D01*
X105130D01*
X104630Y565370D01*
Y567240D01*
X105130Y567740D01*
X117310D01*
X117400Y567650D01*
G01X85175Y572290D02*
X83600Y573865D01*
G01X85175Y569140D02*
Y570165D01*
X85950Y570940D01*
X92330D01*
X93060Y570210D01*
X95560D01*
X96060Y570710D01*
Y572590D01*
X96853Y573383D01*
X102387D01*
X102887Y573883D01*
Y576082D01*
X102886Y576083D01*
X102440Y576530D01*
X96200D01*
X95700Y577030D01*
Y579060D01*
X96340Y579700D01*
X98660D01*
X99750Y580790D01*
Y584540D01*
X100130Y584920D01*
X103255D01*
X103635Y584540D01*
Y581080D01*
X104188Y580527D01*
X106187D01*
X106635Y580975D01*
Y581918D01*
X107135Y582418D01*
X136032D01*
X137432Y581018D01*
Y579130D01*
X137932Y578630D01*
X146236D01*
X146736Y578130D01*
Y576836D01*
X145980Y576080D01*
Y575112D01*
X148052Y573040D01*
X152210D01*
X153236Y574066D01*
X161395D01*
G03X163535Y574953I0J3025D01*
G01X164173Y575590D01*
G01X85175Y578589D02*
Y578590D01*
X83601Y580164D01*
G01X88325Y578589D02*
X89899Y577015D01*
Y577014D01*
G01X85175Y575439D02*
X86750Y577014D01*
G01X85175Y562841D02*
X85174D01*
X83600Y564415D01*
G01X88325Y562841D02*
X88324D01*
X86750Y564415D01*
G01X85175Y559691D02*
X83601Y561265D01*
X83600D01*
G01X88325Y581738D02*
X89675Y583088D01*
X94229D01*
X95587Y581730D01*
X96570D01*
G01X88325Y553392D02*
X87968Y553035D01*
Y553033D01*
X86750Y551815D01*
G01X108600Y570500D02*
X103800D01*
G01D02*
X103683Y570383D01*
X98193D01*
X96950Y569140D01*
X91474D01*
G01X140350Y529700D02*
Y530186D01*
X144432Y534268D01*
Y539132D01*
X145100Y539800D01*
G01X136850Y529700D02*
X135000D01*
X133800Y528500D01*
G01X130450Y534600D02*
Y530300D01*
G01D02*
X132771D01*
X134571Y532100D01*
X139435D01*
X142567Y535232D01*
Y542356D01*
X145012Y544801D01*
G01X126950Y534600D02*
X123200D01*
G01X93744Y542019D02*
X91820Y543943D01*
X91474D01*
G01X154724Y553543D02*
X145843D01*
X138401Y546101D01*
Y543210D01*
X133554Y538363D01*
Y537374D01*
G01X140474Y538335D02*
Y545274D01*
X145100Y549900D01*
G01X126447Y601923D02*
Y605976D01*
X127401Y606930D01*
G01X126447Y601923D02*
Y598454D01*
X126870Y598031D01*
G01X131200Y599250D02*
X129491Y597541D01*
X127360D01*
X126870Y598031D01*
G01X123453Y609818D02*
Y613053D01*
X123500Y613100D01*
G01X132703Y609777D02*
X123494D01*
X123453Y609818D01*
G01X136203Y609777D02*
Y609765D01*
X139959Y606009D01*
G01D02*
X143268Y602700D01*
X147611D01*
X154123Y596188D01*
X156174D01*
X157874Y594488D01*
G01X154724Y597638D02*
X154549D01*
X146900Y605287D01*
Y609878D01*
X141904Y614874D01*
X139971D01*
G01X135468Y617677D02*
X137168D01*
X139971Y614874D01*
G01X128793Y613483D02*
Y616916D01*
X129554Y617677D01*
X131968D01*
G01X128793Y613483D02*
X129376Y612900D01*
X134650D01*
G01X134700Y599250D02*
X137284Y596666D01*
X139728D01*
G01D02*
X146684D01*
X147432Y595918D01*
X151384D01*
X154164Y593138D01*
X156074D01*
X157874Y591338D01*
G01X140500Y620300D02*
Y618634D01*
X148800Y610334D01*
Y604660D01*
X154123Y599337D01*
X156175D01*
X157874Y597638D01*
G01X141971Y624700D02*
X143521Y626250D01*
X145300D01*
G01X109250Y617000D02*
X108750Y616500D01*
X98600D01*
X98200Y616900D01*
G01X109250Y597000D02*
X105600D01*
G01X105400Y601300D02*
X105700Y601000D01*
X109250D01*
G01X104600Y609900D02*
X105500Y609000D01*
X109250D01*
G01Y605000D02*
X106500D01*
X105600Y605900D01*
G01X104600Y614000D02*
X105600Y613000D01*
X109250D01*
G01X104500Y618800D02*
Y620000D01*
X105500Y621000D01*
X109750D01*
G01X123534Y593743D02*
X124250Y594459D01*
X130599D01*
X130600Y594458D01*
X145308D01*
X147416Y592350D01*
X152823D01*
X153835Y591338D01*
X154724D01*
G01X112750Y597000D02*
X115200Y594550D01*
X122727D01*
X123534Y593743D01*
G01X117050Y602000D02*
Y601850D01*
X118100Y600800D01*
Y598100D01*
X117000Y597000D01*
G01X112750Y601000D02*
X116750Y597000D01*
X117000D01*
G01X116200Y611600D02*
X115900D01*
X113300Y609000D01*
X112750D01*
G01X116023Y607423D02*
Y607109D01*
X113914Y605000D01*
X112750D01*
G01Y613000D02*
X114250Y614500D01*
X119000D01*
X119400Y614100D01*
G01X115006Y625751D02*
X116500Y624257D01*
Y621000D01*
G01X113250D02*
Y624701D01*
X114300Y625751D01*
X115006D01*
G01X112750Y617000D02*
X116300D01*
X116400Y616900D01*
G01X131212Y603311D02*
Y606288D01*
X130800Y606700D01*
G01X139679Y601454D02*
X141577D01*
X142431Y600600D01*
X145650D01*
X148467Y597783D01*
X151255D01*
X153938Y595100D01*
X154112D01*
X154724Y594488D01*
G01X134712Y603311D02*
X136569Y601454D01*
X139679D01*
G01X138500Y637900D02*
X142800Y642200D01*
Y644400D01*
X144000Y645600D01*
G01X140700Y650050D02*
X144800D01*
G01X127900Y643420D02*
Y641200D01*
X130500Y638600D01*
G01X127900Y643420D02*
Y647950D01*
G01D02*
X123900D01*
G01X134700Y638600D02*
Y643441D01*
G01X136100Y647950D02*
X132100D01*
G01X134700Y643441D02*
X136100Y644841D01*
Y647950D01*
G01X126150Y636400D02*
Y632300D01*
G01X129903Y634500D02*
X129800D01*
X127600Y632300D01*
X126150D01*
G01X157496Y461248D02*
X149305Y469439D01*
Y488011D01*
X163850Y502556D01*
Y525750D01*
X164850Y526750D01*
Y526767D01*
X166647Y528564D01*
Y532789D01*
X169897Y536039D01*
X171273D01*
X172239Y537005D01*
Y540578D01*
X172606Y540945D01*
X173622D01*
G01X201968Y537795D02*
Y534569D01*
X197750Y530351D01*
Y526760D01*
X199755Y524755D01*
G01X199500Y520450D02*
Y524500D01*
X199755Y524755D01*
G01X201968Y540945D02*
X200488Y539465D01*
Y536922D01*
X193650Y530084D01*
Y526792D01*
X194803Y525639D01*
G01D02*
Y517897D01*
X202800Y509900D01*
G01X201968Y544094D02*
X203424Y542638D01*
Y540729D01*
X205008Y539145D01*
X205678D01*
X206468Y538355D01*
Y533500D01*
X206050Y533082D01*
Y528616D01*
X208000Y526666D01*
Y520500D01*
G01X208100Y515200D02*
X210150Y517250D01*
Y521391D01*
X209850Y521691D01*
Y530084D01*
X210050Y530284D01*
Y533903D01*
X208267Y535686D01*
Y537795D01*
G01X187000Y524214D02*
Y524426D01*
X186450Y524976D01*
Y529246D01*
X186480Y529276D01*
Y530644D01*
X181721Y535403D01*
Y538641D01*
X183071Y539991D01*
Y540945D01*
G01X187000Y524214D02*
Y520450D01*
G01X191100Y519950D02*
X189150Y521900D01*
Y527539D01*
X188584Y528105D01*
G01X177017Y526942D02*
Y532178D01*
X178121Y533282D01*
Y542294D01*
X179921Y544094D01*
G01X177017Y526942D02*
Y525615D01*
X178150Y524482D01*
Y522876D01*
X175744Y520470D01*
X174715D01*
G01X178920Y481548D02*
Y485628D01*
G01X183320Y481548D02*
X183277Y481591D01*
Y485628D01*
G01X178920Y489128D02*
X183277D01*
G01X178920D02*
X169790D01*
X168576Y490342D01*
X163378D01*
X163335Y490299D01*
G01X183277Y489128D02*
Y493077D01*
X183300Y493100D01*
G01X174715Y516970D02*
Y513915D01*
X174700Y513900D01*
G01X187000Y516950D02*
Y513334D01*
X187167Y513167D01*
G01X184167Y506434D02*
Y510167D01*
X187167Y513167D01*
G01X191100Y516450D02*
Y513367D01*
G01X182970Y473998D02*
X212002D01*
X213100Y472900D01*
G01X172800Y524100D02*
X173200Y524500D01*
Y531100D01*
X176771Y534671D01*
Y537795D01*
G01X170700Y520450D02*
Y522000D01*
X172800Y524100D01*
G01X166600Y520450D02*
X166989D01*
X169215Y522676D01*
Y526415D01*
X170200Y527400D01*
G01X178869Y520443D02*
X181024Y522598D01*
Y524357D01*
X182000Y525333D01*
Y527362D01*
G01X182874Y520441D02*
Y523590D01*
G01X160727Y520272D02*
Y522706D01*
X160237Y523196D01*
X160250Y523209D01*
Y525050D01*
X162800Y527600D01*
G01X164173Y537795D02*
Y536614D01*
X158988Y531429D01*
Y530281D01*
X156507Y527800D01*
X154686D01*
X153812Y526926D01*
G01X150112Y516548D02*
Y516912D01*
X151499Y518299D01*
Y524543D01*
X153812Y526856D01*
Y526926D01*
G01X158100Y524100D02*
Y525800D01*
X161036Y528736D01*
Y530603D01*
X167323Y536890D01*
Y537795D01*
G01X156721Y520242D02*
Y522721D01*
X158100Y524100D01*
G01X164173Y540945D02*
X162695Y539467D01*
Y536991D01*
X157695Y531991D01*
Y530261D01*
X156384Y528950D01*
X155016D01*
X154990Y528976D01*
X149783D01*
X148400Y527593D01*
Y523100D01*
X146112Y520812D01*
Y516548D01*
G01X205516Y467968D02*
Y466238D01*
X211454Y460300D01*
X220521D01*
G01X177791Y495710D02*
X181002Y498921D01*
Y502877D01*
X174079Y509800D01*
X170700D01*
G01X174291Y495710D02*
X171001D01*
X170633Y495342D01*
X163378D01*
X163335Y495299D01*
G01X190950Y482100D02*
Y493510D01*
X189575Y494885D01*
Y501675D01*
X188400Y502850D01*
G01X197350Y502800D02*
X197200Y502950D01*
X193000D01*
G01X197350Y502800D02*
Y498333D01*
X196067Y497050D01*
X196033D01*
X194250Y495267D01*
Y484550D01*
X196200Y482600D01*
G01X200100Y491700D02*
X200074Y491726D01*
Y492124D01*
X200150Y492200D01*
Y495600D01*
G01X179494Y469867D02*
Y473974D01*
X179470Y473998D01*
G01X164039Y470299D02*
X172107D01*
X172539Y469867D01*
X179494D01*
G01X205118Y537795D02*
Y534384D01*
X201960Y531226D01*
Y527358D01*
X204752Y524566D01*
G01X203500Y520350D02*
X204752Y521602D01*
Y524566D01*
G01X193000Y506450D02*
Y507779D01*
X195379Y510158D01*
G01X203542Y592913D02*
X205117Y591338D01*
X205118D01*
G01X168898Y548819D02*
X170472Y550393D01*
Y550394D01*
G01X208267Y572441D02*
X206692Y574016D01*
G01X165745Y564567D02*
X167320Y566142D01*
X167323D01*
G01X168895Y564567D02*
X170470Y566142D01*
X170472D01*
G01X159449Y561417D02*
X161023Y562991D01*
Y562992D01*
G01X164173D02*
X165748Y561417D01*
G01X170472Y562992D02*
X172047Y561417D01*
G01X162598Y558268D02*
X164172Y559842D01*
X164173D01*
G01X168898Y558268D02*
X167324Y559842D01*
X167323D01*
G01X164173Y556693D02*
X165748Y555118D01*
G01X159449D02*
X161023Y556692D01*
Y556693D01*
G01X170472Y569291D02*
X168898Y567717D01*
G01X159449Y570866D02*
X161023Y572440D01*
Y572441D01*
G01X170472Y581890D02*
X168898Y583464D01*
G01Y577165D02*
X170472Y575591D01*
Y575590D01*
G01X159449Y586614D02*
X161023Y585040D01*
Y585039D01*
G01X164173Y581890D02*
X162598Y580315D01*
G01X164173Y585039D02*
X162598Y586614D01*
G01X167323Y585039D02*
X165748Y586614D01*
G01X168898D02*
X170472Y585040D01*
Y585039D01*
G01X159449Y577165D02*
X161023Y575591D01*
Y575590D01*
G01X157874D02*
X156299Y577165D01*
G01X168898Y580315D02*
X170472Y578741D01*
Y578740D01*
G01X159449Y580315D02*
X161023Y578741D01*
Y578740D01*
G01X164173D02*
X162598Y577165D01*
G01X167323Y578740D02*
X165748Y580315D01*
G01X162598Y583464D02*
X161024Y581890D01*
X161023D01*
G01X167323Y572441D02*
X165748Y570866D01*
G01Y567717D02*
X164174Y569291D01*
X164173D01*
G01X162598Y567717D02*
X161024Y569291D01*
X161023D01*
G01X190945Y542519D02*
X189370Y544094D01*
G01X173622Y547244D02*
X172047Y545669D01*
G01X173622Y553543D02*
X172047Y551970D01*
G01X159449Y545671D02*
X159450D01*
X161023Y547244D01*
G01X162599Y545669D02*
X164173Y547243D01*
Y547244D01*
G01X165749Y545669D02*
X167323Y547243D01*
Y547244D01*
G01X184646Y548821D02*
X184647D01*
X186220Y550394D01*
G01X184646Y545671D02*
X184647D01*
X186220Y547244D01*
G01X209842Y567717D02*
X209841D01*
X208267Y569291D01*
G01X188584Y528105D02*
X188183Y528506D01*
Y532683D01*
X183071Y537795D01*
G01X184645Y542519D02*
X186220Y544094D01*
G01X206692Y542521D02*
X206691D01*
X205118Y544094D01*
G01X209841Y577165D02*
Y577164D01*
X208267Y575590D01*
G01X159449Y542521D02*
X161022Y544094D01*
X161023D01*
G01X168390Y532060D02*
X169495D01*
X173622Y536187D01*
Y537795D01*
G01X154724Y547244D02*
X152980Y545500D01*
X150800D01*
X145100Y539800D01*
G01X156299Y545671D02*
X156301D01*
X157874Y547244D01*
G01X168898Y592913D02*
Y592912D01*
X170472Y591338D01*
G01X181497Y545671D02*
X183070Y547244D01*
X183071D01*
G01X208267D02*
X209842Y545669D01*
G01X165749Y548819D02*
X167323Y550393D01*
Y550394D01*
G01X175197Y545671D02*
X175198D01*
X176771Y547244D01*
G01X162599Y542519D02*
X164173Y544093D01*
Y544094D01*
G01X168898Y542519D02*
X170472Y544093D01*
Y544094D01*
G01X156299Y542521D02*
X156301D01*
X157874Y544094D01*
G01X170200Y527400D02*
X171513Y528713D01*
Y532010D01*
X174995Y535492D01*
Y539169D01*
X176771Y540945D01*
G01X179921Y537795D02*
Y534375D01*
X182000Y532296D01*
Y527362D01*
G01X181496Y542520D02*
X179921Y540945D01*
G01X162800Y527600D02*
X164256Y529056D01*
Y532544D01*
X168800Y537088D01*
Y539273D01*
X170472Y540945D01*
G01X159449Y548821D02*
X159450D01*
X161023Y550394D01*
G01X206692Y589763D02*
X206693D01*
X208267Y588189D01*
G01X145012Y544801D02*
X147469Y547258D01*
X152755D01*
X154297Y548800D01*
X155383D01*
X156977Y550394D01*
X157874D01*
G01X173622D02*
X172047Y548819D01*
G01X170472Y553543D02*
X168898Y551969D01*
G01X162599Y548821D02*
X162600D01*
X164173Y550394D01*
G01X194093Y592913D02*
X192519Y591339D01*
Y591338D01*
G01X194093Y589764D02*
Y589763D01*
X192519Y588189D01*
G01X161023Y559842D02*
X162598Y561417D01*
G01X168898Y555119D02*
X170472Y556692D01*
Y556693D01*
G01X181497Y548821D02*
X181498D01*
X183071Y550394D01*
G01X178346Y545670D02*
X179920Y547244D01*
X179921D01*
G01X208267Y585039D02*
X206692Y586614D01*
G01X162595Y564567D02*
X162596D01*
X164171Y566142D01*
X164173D01*
G01Y572441D02*
X162598Y570866D01*
G01X203542Y548821D02*
Y551969D01*
X201968Y553543D01*
G01X154724Y550394D02*
X154230Y549900D01*
X145100D01*
G01X209842Y558268D02*
X209841D01*
X208267Y559842D01*
G01X192519Y544094D02*
X194094Y542519D01*
G01X208267Y566142D02*
X209842Y564567D01*
G01X200393Y548819D02*
X198819Y550393D01*
Y550394D01*
G01X208267Y562992D02*
X209842Y561417D01*
G01X206692Y580315D02*
X205118Y578741D01*
Y578740D01*
G01X209841Y580315D02*
Y580314D01*
X208267Y578740D01*
G01X200393Y545669D02*
X198819Y547243D01*
Y547244D01*
G01X206692Y545671D02*
X208267Y544096D01*
Y544094D01*
G01X149242Y531080D02*
X153476D01*
X157874Y535478D01*
Y537795D01*
G01X200393Y592913D02*
X201968Y591338D01*
G01X161023Y588189D02*
X159448Y589764D01*
G01X161023Y591338D02*
X159448Y592913D01*
G01X164173Y588189D02*
X162598Y589764D01*
G01X167323Y588189D02*
X165748Y589764D01*
G01X167323Y591338D02*
X165748Y592913D01*
G01X205118Y540945D02*
X206100D01*
X207773Y539272D01*
X208700D01*
X209882Y538090D01*
Y537254D01*
X213250Y533886D01*
Y528716D01*
X213487Y528479D01*
Y524273D01*
G01X165749Y542519D02*
Y542520D01*
X167323Y544094D01*
G01X176771Y591338D02*
X175197Y592912D01*
Y592913D01*
G01X173622Y591338D02*
Y591339D01*
X172048Y592913D01*
G01X208267Y556693D02*
X208268D01*
X209842Y555119D01*
G01X208267Y553543D02*
X208268D01*
X209842Y551969D01*
G01X181497Y592913D02*
Y592912D01*
X183071Y591338D01*
G01X195669Y547244D02*
X197244Y545669D01*
G01X194094Y548820D02*
Y548994D01*
X195494Y550394D01*
X195669D01*
G01X208267D02*
X209842Y548819D01*
G01X152584Y532922D02*
X151425Y534081D01*
Y536690D01*
X154724Y539989D01*
Y540945D01*
G01X152415Y540014D02*
X152792Y540391D01*
Y542162D01*
X154724Y544094D01*
G01X176771Y550394D02*
X176770D01*
X175197Y548821D01*
G01X168898Y545669D02*
X170472Y547243D01*
Y547244D01*
G01X157874Y540945D02*
X156300Y539371D01*
G01X195669Y544094D02*
X194094Y545669D01*
G01X198819Y540945D02*
X197244Y542520D01*
G01X206692Y596063D02*
X205118Y594489D01*
Y594488D01*
G01X216000Y622450D02*
X214850Y621300D01*
Y613650D01*
X208267Y607067D01*
Y603937D01*
G01Y600787D02*
X209862Y602382D01*
Y606362D01*
X217750Y614250D01*
Y620922D01*
X219450Y622622D01*
Y631849D01*
X221691Y634091D01*
X223593D01*
G01X190945Y599213D02*
X189370Y597638D01*
G01X190944Y596063D02*
X189370Y594489D01*
Y594488D01*
G01X194200Y613700D02*
Y608686D01*
X192054Y606540D01*
X191660D01*
X189370Y604250D01*
Y603937D01*
G01X193285Y621050D02*
X192851Y620616D01*
Y615320D01*
X194200Y613971D01*
Y613700D01*
G01X189185Y617400D02*
Y610885D01*
X184707Y606407D01*
Y602423D01*
X183071Y600787D01*
G01X189185Y621050D02*
Y617400D01*
G01X185085Y621050D02*
Y613700D01*
G01D02*
Y609884D01*
X183071Y607870D01*
Y603937D01*
G01X182200Y617100D02*
Y619935D01*
X181085Y621050D01*
G01X182200Y617100D02*
Y613601D01*
X179921Y611322D01*
Y603937D01*
G01Y600787D02*
X178121Y602587D01*
Y611621D01*
X178800Y612300D01*
Y614100D01*
G01D02*
Y618150D01*
X177000Y619950D01*
G01X175040Y616035D02*
Y610231D01*
X176771Y608500D01*
Y603937D01*
G01X172900Y619950D02*
Y618175D01*
X175040Y616035D01*
G01X176771Y600787D02*
Y601687D01*
X175348Y603110D01*
Y605100D01*
X173310Y607138D01*
Y614600D01*
X170899Y617011D01*
Y622201D01*
X170450Y622650D01*
Y622791D01*
X169191Y624050D01*
X169050D01*
X163300Y629800D01*
G01X164800Y633550D02*
X168900D01*
G01X163300Y629800D02*
Y632050D01*
X164800Y633550D01*
G01X187796Y599212D02*
X189370Y600786D01*
Y600787D01*
G01X184645Y599213D02*
Y599212D01*
X183071Y597638D01*
G01X174100Y628900D02*
Y630550D01*
X177100Y633550D01*
G01X174100Y628900D02*
Y626800D01*
X177000Y623900D01*
Y623450D01*
G01X168800Y628400D02*
Y629350D01*
X173000Y633550D01*
G01X168800Y628400D02*
Y627550D01*
X172900Y623450D01*
G01X161023Y594488D02*
X159448Y596063D01*
G01X197315Y622347D02*
Y617778D01*
G01D02*
X198400Y616693D01*
Y611613D01*
X192427Y605640D01*
X192033D01*
X190944Y604551D01*
Y602362D01*
X192519Y600787D01*
G01X202560Y624016D02*
X201449Y622905D01*
Y619094D01*
G01D02*
Y617897D01*
X202529Y616817D01*
Y614055D01*
X192693Y604219D01*
X192692D01*
X192519Y604046D01*
Y603937D01*
G01X196249Y630091D02*
Y629969D01*
X196110Y629830D01*
Y627052D01*
X197315Y625847D01*
G01X199400Y628646D02*
X201430D01*
X202560Y627516D01*
G01X199400Y628646D02*
X198749Y629297D01*
Y632013D01*
X197555Y633207D01*
G01X153700Y626250D02*
Y626294D01*
X152250Y627744D01*
Y629100D01*
X151550Y629800D01*
G01X147800Y633850D02*
Y633162D01*
X151162Y629800D01*
X151550D01*
G01X168898Y596063D02*
Y596062D01*
X170472Y594488D01*
G01X185085Y624550D02*
X183834Y625801D01*
Y629284D01*
X184050Y629500D01*
G01D02*
X185276Y630726D01*
Y632818D01*
G01X181085Y624550D02*
Y627058D01*
X181176Y627149D01*
Y627600D01*
G01D02*
Y633528D01*
X181146Y633558D01*
G01X203542Y602362D02*
Y602361D01*
X201968Y600787D01*
G01X203542Y599213D02*
X201968Y597639D01*
Y597638D01*
G01X206692Y602362D02*
Y602361D01*
X205118Y600787D01*
G01X207900Y637950D02*
X211698D01*
X211706Y637942D01*
G01X201968Y594488D02*
Y594489D01*
X203542Y596063D01*
G01X200850Y642950D02*
X202900D01*
X207900Y637950D01*
G01X194094Y599213D02*
X192519Y597638D01*
G01X164173Y594488D02*
X162598Y596063D01*
G01X167323Y597638D02*
X165748Y599213D01*
G01X168898D02*
Y599212D01*
X170472Y597638D01*
G01X164173D02*
X162598Y599213D01*
G01X161023Y597638D02*
X159448Y599213D01*
G01X172048Y596063D02*
Y596062D01*
X173622Y594488D01*
G01X149250Y618050D02*
Y622600D01*
X149400Y622750D01*
G01X149250Y618050D02*
Y614950D01*
X158813Y605387D01*
X161624D01*
X162473Y604538D01*
Y603727D01*
X163613Y602587D01*
X165523D01*
X167323Y600787D01*
G01X144550Y618316D02*
Y616706D01*
X151120Y610136D01*
Y605349D01*
X154232Y602237D01*
X162000D01*
X163450Y600787D01*
X164173D01*
G01X145300Y622750D02*
X144550Y622000D01*
Y618316D01*
G01X146800Y629900D02*
X147700Y629000D01*
Y627950D01*
X149400Y626250D01*
G01X173622Y600787D02*
X172000Y602409D01*
Y604500D01*
X166710Y609790D01*
Y612100D01*
X164398Y614412D01*
Y625282D01*
X164130Y625550D01*
G01X168300Y621900D02*
X168580Y621620D01*
Y609193D01*
X172900Y604873D01*
Y604659D01*
X173622Y603937D01*
G01X158350Y629040D02*
X158700Y628690D01*
Y627240D01*
X161370Y624570D01*
Y621990D01*
X162898Y620462D01*
Y614639D01*
X163498Y614039D01*
Y614038D01*
X164024Y613512D01*
X164025D01*
X165810Y611727D01*
Y609417D01*
X166300Y608927D01*
Y608812D01*
X169612Y605500D01*
Y604797D01*
X170472Y603937D01*
G01X159200Y623240D02*
Y621538D01*
X161398Y619340D01*
Y614206D01*
X164850Y610754D01*
Y608320D01*
X168570Y604600D01*
X168712D01*
Y602547D01*
X170472Y600787D01*
G01X178346Y596064D02*
X179921Y594489D01*
Y594488D01*
G01X178347Y599213D02*
X179921Y597639D01*
Y597638D01*
G01X181540Y644450D02*
Y641300D01*
X180700Y640460D01*
G01X153901Y617796D02*
Y612733D01*
X160347Y606287D01*
X162513D01*
X164173Y604627D01*
Y603937D01*
G01X153700Y622750D02*
Y619655D01*
X153901Y619454D01*
Y617796D01*
G01X183071Y594488D02*
X183070D01*
X181496Y596062D01*
G01X212445Y653538D02*
Y652145D01*
X211400Y651100D01*
X209210D01*
X204358Y646248D01*
Y646150D01*
X204150Y645942D01*
Y645180D01*
G01X212445Y653538D02*
X208603D01*
X208516Y653451D01*
G01D02*
X204372D01*
X204357Y653436D01*
G01X208267Y597638D02*
X209841Y599212D01*
G01X205118Y597638D02*
Y597639D01*
X206692Y599213D01*
G01X200532Y653653D02*
X196730D01*
X196648Y653571D01*
G01D02*
X191767D01*
X191746Y653592D01*
G01X200532Y653653D02*
Y651032D01*
X199600Y650100D01*
G01X167323Y594488D02*
X165748Y596063D01*
G01X192960Y628510D02*
Y628440D01*
X193285Y628115D01*
Y624550D01*
G01X193476Y632818D02*
X192960Y632302D01*
Y628510D01*
G01X189376Y632818D02*
Y630346D01*
X187900Y628870D01*
Y628500D01*
G01D02*
Y627746D01*
X189185Y626461D01*
Y624550D01*
G01X158898Y617993D02*
Y617992D01*
X158230Y617324D01*
Y609677D01*
X160720Y607187D01*
X164073D01*
X167323Y603937D01*
G01X152700Y640800D02*
X154100Y639400D01*
X154498Y639001D01*
Y636098D01*
X152250Y633850D01*
X151900D01*
G01D02*
Y632987D01*
X154050Y630837D01*
Y630836D01*
X154750Y630136D01*
Y628780D01*
X156200Y627330D01*
Y625213D01*
X156160Y625173D01*
Y623827D01*
X156200Y623787D01*
Y620691D01*
X158898Y617993D01*
G01X190200Y671000D02*
X186400Y667200D01*
Y664777D01*
X172473Y650850D01*
X168100D01*
X165000Y647750D01*
G01X161000D02*
X165000D01*
G01X161000Y634300D02*
X160200Y635100D01*
Y639600D01*
G01D02*
Y643450D01*
X161000Y644250D01*
G01X149300Y648450D02*
X153300D01*
X153350Y648400D01*
G01X149300Y648450D02*
Y651000D01*
X151700Y653400D01*
X171487D01*
X183900Y665813D01*
Y669500D01*
X187500Y673100D01*
G01X156850Y648400D02*
X156238Y647788D01*
Y643866D01*
G01D02*
X157200Y642904D01*
Y634200D01*
G01X144800Y650050D02*
Y646400D01*
X144000Y645600D01*
G01X176771Y594488D02*
Y594489D01*
X175197Y596063D01*
G01X176771Y597638D02*
Y597639D01*
X175197Y599213D01*
G01X173622Y597638D02*
Y597639D01*
X172048Y599213D01*
G01X267950Y458200D02*
X265671D01*
X263571Y460300D01*
X259079D01*
G01X259000Y453900D02*
X259900Y453000D01*
X274200D01*
X281300Y460100D01*
X294210D01*
X303220Y451090D01*
X349865D01*
X349866Y451091D01*
X353909D01*
X356100Y448900D01*
X379300D01*
X386677Y441523D01*
Y370695D01*
X383140Y367158D01*
G01X383900Y422100D02*
Y433502D01*
X370702Y446700D01*
X355300D01*
X352909Y449091D01*
X350695D01*
X350694Y449090D01*
X302391D01*
X297181Y454300D01*
X285900D01*
X283900Y456300D01*
X280400D01*
X275100Y451000D01*
X259071D01*
X258910Y451161D01*
X258909D01*
X258020Y452050D01*
X254050D01*
X252100Y454000D01*
X247500D01*
X244700Y451200D01*
G01X352017Y263432D02*
X356877Y268292D01*
Y365435D01*
X373376Y381934D01*
Y435539D01*
X368215Y440700D01*
X352400D01*
X350010Y443090D01*
X297510D01*
X293500Y447100D01*
X276858D01*
X276758Y447000D01*
X257412D01*
X256712Y447700D01*
X248300D01*
X247300Y448700D01*
X239700D01*
X236100Y445100D01*
G01X239300Y443800D02*
Y445000D01*
X240600Y446300D01*
X243500D01*
X250500Y439300D01*
X291042D01*
X293252Y437090D01*
X347381D01*
X349771Y434700D01*
X365728D01*
X367376Y433052D01*
Y385810D01*
X361176Y379610D01*
G01X243000Y443800D02*
X249500Y437300D01*
X288200D01*
X292800Y432700D01*
X364899D01*
X365211Y432388D01*
Y424805D01*
X365376Y424640D01*
Y386888D01*
X354850Y376362D01*
G01X247900Y445300D02*
X248300Y445700D01*
X255883D01*
X256583Y445000D01*
X264600D01*
X266300Y443300D01*
X292700D01*
X294910Y441090D01*
X349039D01*
X351429Y438700D01*
X367386D01*
X371376Y434710D01*
Y382763D01*
X354877Y366265D01*
Y270633D01*
X348618Y264374D01*
X340339D01*
X334998Y259033D01*
G01X335060Y262516D02*
X338918Y266374D01*
X347789D01*
X352877Y271462D01*
Y367094D01*
X369376Y383593D01*
Y433881D01*
X366557Y436700D01*
X350600D01*
X348210Y439090D01*
X294081D01*
X291871Y441300D01*
X265200D01*
X263900Y442600D01*
X260600D01*
G01X250500Y451300D02*
X251750Y450050D01*
X257191D01*
X258241Y449000D01*
X275929D01*
X276679Y449750D01*
X295050D01*
X299710Y445090D01*
X351052D01*
X353442Y442700D01*
X369044D01*
X378600Y433144D01*
Y388000D01*
X380677Y385923D01*
Y376127D01*
X369300Y364750D01*
Y362600D01*
G01X269600Y523350D02*
Y528050D01*
G01X286797Y516522D02*
X276428D01*
X269600Y523350D01*
G01X211417Y537795D02*
X216550Y532662D01*
Y526761D01*
X216311Y526522D01*
Y522945D01*
X217100Y522156D01*
Y520300D01*
G01X268350Y490300D02*
Y493909D01*
X264082Y498177D01*
X256170D01*
X254500Y499847D01*
Y509600D01*
G01X259079Y490300D02*
X268350D01*
G01X271350Y474500D02*
X275200D01*
G01X227500Y512200D02*
X225600Y514100D01*
Y515330D01*
G01X228700Y490717D02*
Y510783D01*
X229950Y512033D01*
Y514918D01*
X230262Y515230D01*
G01X225300Y527900D02*
Y526000D01*
X224064Y524764D01*
Y522284D01*
X225198Y521150D01*
X227350D01*
X229770Y518730D01*
X230262D01*
G01X230700Y486658D02*
Y489517D01*
X234348Y493165D01*
Y515164D01*
G01X217716Y540945D02*
X219416Y539245D01*
X221750D01*
X225544Y535451D01*
Y533456D01*
X229154Y529846D01*
Y527363D01*
X230000Y526517D01*
Y524300D01*
X231800Y522500D01*
G01X234348Y518664D02*
Y519952D01*
X231800Y522500D01*
G01X250700Y530500D02*
Y528800D01*
X249050Y527150D01*
G01X249640Y495080D02*
X249680D01*
X249900Y495300D01*
X258375D01*
G01X209256Y467946D02*
Y466432D01*
X210388Y465300D01*
X220521D01*
G01X238648Y518664D02*
Y519752D01*
X231204Y527196D01*
Y529404D01*
G01X242700Y515170D02*
X238654D01*
X238648Y515164D01*
G01D02*
X236500Y513016D01*
Y492700D01*
X234700Y490900D01*
G01X301620Y515600D02*
X299500D01*
X291483Y507583D01*
X257679D01*
X256500Y508762D01*
Y510217D01*
X255267Y511450D01*
X238550D01*
X238400Y511300D01*
G01X225600Y518830D02*
X225396D01*
X221800Y522426D01*
Y523700D01*
G01D02*
X219400Y526100D01*
Y533100D01*
X216266Y536234D01*
Y538147D01*
X215113Y539300D01*
X213062D01*
X211417Y540945D01*
G01X258375Y470300D02*
X259079D01*
G01X267950D02*
X267850Y470400D01*
Y474500D01*
G01X259079Y470300D02*
X267950D01*
G01X212150Y499300D02*
Y495300D01*
G01X210000Y510000D02*
X212150Y507850D01*
Y499300D01*
G01X216900Y515716D02*
X219966D01*
X221187Y516937D01*
G01D02*
Y520191D01*
X217811Y523567D01*
Y533416D01*
X214567Y536660D01*
Y537795D01*
G01X212600Y520450D02*
Y523386D01*
X213487Y524273D01*
G01X265274Y509512D02*
Y513675D01*
X254731Y524218D01*
X245082D01*
X240800Y528500D01*
G01X238200Y524600D02*
Y525308D01*
X232006Y531502D01*
X230898D01*
X228130Y534270D01*
Y536830D01*
X220866Y544094D01*
G01X216141Y580315D02*
X214567Y578741D01*
Y578740D01*
G01X274245Y546834D02*
Y542274D01*
X272723Y540752D01*
G01X269600Y531550D02*
X267800D01*
X264250Y535100D01*
Y539500D01*
G01X272723Y540752D02*
X271471Y539500D01*
X264250D01*
G01X216141Y577165D02*
Y577164D01*
X214567Y575590D01*
G01X212991Y567718D02*
X212990D01*
X211417Y569291D01*
G01X209841Y574016D02*
X211416Y572441D01*
X211417D01*
G01X216141Y583465D02*
X214567Y581891D01*
Y581890D01*
G01X216141Y564569D02*
X214568Y566142D01*
X214567D01*
G01X246800Y541900D02*
X243400Y545300D01*
Y545981D01*
X243393Y545988D01*
Y548292D01*
X241767Y549918D01*
X239059D01*
X236908Y552069D01*
Y553153D01*
X235111Y554950D01*
X235054D01*
X234487Y555517D01*
X233144D01*
X230911Y557750D01*
X230350D01*
X226821Y561279D01*
Y561840D01*
X224311Y564350D01*
X219650D01*
X217858Y566142D01*
X217716D01*
G01X211417Y562992D02*
X212992Y561417D01*
G01X216141Y567718D02*
X214568Y569291D01*
X214567D01*
G01X219293Y567717D02*
X220866Y569290D01*
Y569291D01*
G01X217716D02*
X218956D01*
X220306Y570641D01*
X221426D01*
X223659Y568408D01*
X228433D01*
X230940Y565901D01*
G01D02*
X233100Y563741D01*
Y562500D01*
X234902Y560698D01*
X240546D01*
G01Y564798D02*
X238548Y562800D01*
X236700D01*
G01X211417Y578740D02*
X212992Y580315D01*
G01X236700Y562800D02*
X236000D01*
X234943Y563857D01*
Y565199D01*
G01X212991Y577165D02*
Y577164D01*
X211417Y575590D01*
G01X212991Y574016D02*
X214566Y572441D01*
X214567D01*
G01X217716D02*
X216141Y574016D01*
G01X220866Y572441D02*
X221766Y571541D01*
X221799D01*
X223090Y570250D01*
X230849D01*
X232820Y568279D01*
X235339D01*
G01X239568Y568821D02*
X239026Y568279D01*
X235339D01*
G01X239568Y572821D02*
X237976D01*
X235721Y575076D01*
G01D02*
X221380D01*
X220866Y575590D01*
G01X239850Y581100D02*
X239529D01*
X236210Y584419D01*
G01X220866Y578740D02*
X224065D01*
X228986Y583661D01*
X231796D01*
X232554Y584419D01*
X236210D01*
G01X232763Y579124D02*
X229034D01*
X227300Y577390D01*
X219066D01*
X217716Y578740D01*
G01X239950Y576900D02*
X237726Y579124D01*
X232763D01*
G01X216141Y561419D02*
X216140D01*
X214567Y562992D01*
G01X220866Y566142D02*
X225802D01*
X229022Y562922D01*
Y561978D01*
X231200Y559800D01*
G01D02*
X234527D01*
X234529Y559798D01*
X235214D01*
X238354Y556658D01*
X239520D01*
G01X212991Y583465D02*
X211417Y581891D01*
Y581890D01*
G01X212991Y542519D02*
X211417Y544093D01*
Y544094D01*
G01X274245Y551954D02*
X267796D01*
X267650Y552100D01*
G01D02*
X267200Y551650D01*
Y548200D01*
G01D02*
Y543850D01*
X267291Y543759D01*
G01X254824Y552061D02*
X254153Y551390D01*
X252865D01*
X251694Y550219D01*
X249998D01*
G01X243020Y556658D02*
X244837D01*
X249998Y551497D01*
Y550219D01*
G01X263791Y543759D02*
X261859D01*
X260800Y542700D01*
X260741D01*
G01X264333Y528926D02*
X259800D01*
G01D02*
X259670Y529056D01*
Y532870D01*
G01X225300Y527900D02*
X223900D01*
X220900Y530900D01*
Y533925D01*
X217716Y537109D01*
Y537795D01*
G01X247946Y556761D02*
X250085Y558900D01*
X252284D01*
X254905Y556279D01*
Y555761D01*
G01X244046Y560698D02*
X245902D01*
X247946Y558654D01*
Y556761D01*
G01X258528Y555161D02*
Y555291D01*
X258500Y555319D01*
Y558526D01*
X257161Y559865D01*
G01X248027Y563068D02*
X250195Y560900D01*
X256126D01*
X257161Y559865D01*
G01X244046Y564798D02*
X246297D01*
X248027Y563068D01*
G01X243068Y568821D02*
X246303D01*
X248016Y567108D01*
G01X259100Y567706D02*
X257700Y569106D01*
X255965D01*
X255471Y569600D01*
X253369D01*
X252818Y569049D01*
X249957D01*
X248016Y567108D01*
G01X257000Y571700D02*
X256550Y572150D01*
X253090D01*
X251989Y571049D01*
X249711D01*
X247990Y572770D01*
Y573160D01*
X247650Y573500D01*
G01D02*
X243747D01*
X243068Y572821D01*
G01X239560Y537139D02*
X238599Y538100D01*
X230466D01*
X221322Y547244D01*
X220866D01*
G01X239560Y537139D02*
Y535485D01*
X242243Y532802D01*
G01X250700Y530500D02*
Y532085D01*
X248024Y534761D01*
X244525D01*
X242566Y532802D01*
X242243D01*
G01X209842Y586613D02*
X209843D01*
X211417Y585039D01*
G01X212992Y589764D02*
X211418Y591338D01*
X211417D01*
G01X251550Y590200D02*
X249000Y587650D01*
X246407D01*
X243757Y585000D01*
X241300D01*
G01D02*
X240250Y586050D01*
Y588900D01*
G01D02*
X238617D01*
X237867Y588150D01*
X235012D01*
X231850Y584988D01*
X228548D01*
X224100Y580540D01*
X219560D01*
X218210Y581890D01*
X217716D01*
G01X237000Y597400D02*
Y597100D01*
X230210Y590310D01*
X226610D01*
X222700Y586400D01*
X219077D01*
X217716Y585039D01*
G01X220866Y540945D02*
X221319Y540492D01*
X221776D01*
X226884Y535384D01*
Y533724D01*
X231204Y529404D01*
G01X212992Y555119D02*
X212991D01*
X211417Y556693D01*
G01X212992Y558268D02*
X212991D01*
X211417Y559842D01*
G01X216142Y548820D02*
X214568Y550394D01*
X214567D01*
G01X217716Y556693D02*
X219409Y555000D01*
X223141D01*
X229750Y548391D01*
Y546908D01*
X235562Y541096D01*
G01X216141Y555120D02*
X216140D01*
X214567Y556693D01*
G01X241100Y541600D02*
X238988Y543712D01*
X235702D01*
X229963Y549451D01*
Y552853D01*
X228997Y553819D01*
X228944D01*
Y553872D01*
X224369Y558447D01*
X219111D01*
X217716Y559842D01*
G01X216141Y558269D02*
X216140D01*
X214567Y559842D01*
G01X240900Y547300D02*
X239555D01*
X235408Y551447D01*
Y552531D01*
X234489Y553450D01*
X234432D01*
X233865Y554017D01*
X232783D01*
X224396Y562404D01*
X221454D01*
X220866Y562992D01*
G01Y559842D02*
X224247D01*
X230863Y553226D01*
Y550437D01*
X233000Y548300D01*
X235400D01*
X235500Y548200D01*
G01X235600Y611800D02*
X231510Y607710D01*
X230937D01*
X228600Y605373D01*
Y604153D01*
X225230Y600783D01*
Y599023D01*
X224800Y598593D01*
Y596264D01*
X221224Y592688D01*
X220306D01*
X218956Y591338D01*
X217716D01*
G01X222441Y548820D02*
X220867Y550394D01*
X220866D01*
G01X219291Y548820D02*
X217717Y550394D01*
X217716D01*
G01X212992Y551969D02*
X211418Y553543D01*
X211417D01*
G01X216141Y551970D02*
X214568Y553543D01*
X214567D01*
G01X228100Y545500D02*
Y548580D01*
X223137Y553543D01*
X220866D01*
G01X228800Y542100D02*
X225800Y545100D01*
Y549607D01*
X223307Y552100D01*
X219159D01*
X217716Y553543D01*
G01X228313Y552169D02*
X227831D01*
X223307Y556693D01*
X220866D01*
G01X211417Y550394D02*
X212992Y548819D01*
G01X262000Y586900D02*
X261740Y586640D01*
X260740D01*
X257600Y583500D01*
X249850D01*
X247650Y585700D01*
G01X243350Y581100D02*
Y581400D01*
X247650Y585700D01*
G01X247400Y578300D02*
X247990Y578890D01*
Y579280D01*
X249761Y581051D01*
X252161D01*
X253361Y582251D01*
X255680D01*
X257851Y580080D01*
G01X247400Y578300D02*
X244850D01*
X243450Y576900D01*
G01X273317Y557480D02*
X270191D01*
X270145Y557526D01*
G01X267200Y576400D02*
Y577700D01*
X267600Y578100D01*
Y582000D01*
G01X274250Y575000D02*
X268600D01*
X267200Y576400D01*
G01X216141Y589762D02*
X214567Y591336D01*
Y591338D01*
G01X209842Y589763D02*
X211416Y588189D01*
X211417D01*
G01X240300Y613737D02*
X239078D01*
X237750Y612409D01*
Y610909D01*
X236491Y609650D01*
X235370D01*
X226130Y600410D01*
Y598650D01*
X225700Y598220D01*
Y595301D01*
X221737Y591338D01*
X220866D01*
G01X257891Y563786D02*
X261500Y567300D01*
X262850D01*
G01D02*
Y568200D01*
X266750Y572100D01*
G01X257600Y576500D02*
X259700Y574400D01*
X264450D01*
X266750Y572100D01*
G01X211417Y566142D02*
X212992Y564567D01*
G01X239520Y552558D02*
X239419D01*
Y552764D01*
X235733Y556450D01*
X235676D01*
X235109Y557017D01*
X234261D01*
X233607Y557671D01*
G01X234800Y572000D02*
X233009Y573791D01*
X220755D01*
X218956Y575590D01*
X217716D01*
G01X211417Y547244D02*
X212992Y545669D01*
G01X240800Y528500D02*
X232903Y536397D01*
X230614D01*
X221355Y545656D01*
X219304D01*
X217716Y547244D01*
G01X216142Y545669D02*
X214567Y547244D01*
G01X252590Y538010D02*
Y536450D01*
X256170Y532870D01*
G01X252590Y538010D02*
Y542010D01*
X248900Y545700D01*
G01X267957Y537304D02*
X280264Y524997D01*
X287615D01*
G01X271357Y537253D02*
X280781Y527829D01*
X291186D01*
X292057Y528700D01*
X295363D01*
X296794Y530131D01*
X298308D01*
G01X278900Y602700D02*
Y599650D01*
X271250Y592000D01*
X267600D01*
G01X233036Y550942D02*
X233017Y550961D01*
Y552345D01*
X224162Y561200D01*
X219508D01*
X217716Y562992D01*
G01X216000Y622450D02*
X217400Y623850D01*
Y634370D01*
X215406Y636364D01*
Y637942D01*
G01X223400Y637950D02*
X221800D01*
X219200Y640550D01*
G01D02*
X218014D01*
X215406Y637942D01*
G01X231300Y642050D02*
Y639150D01*
X232850Y637600D01*
G01X231300Y642050D02*
X227500D01*
G01D02*
Y639550D01*
X225250Y637300D01*
Y635748D01*
X223593Y634091D01*
G01X229796Y610104D02*
X227264Y607572D01*
Y604090D01*
X224330Y601156D01*
Y599396D01*
X223900Y598966D01*
Y598550D01*
X221416Y596066D01*
X219294D01*
X217716Y594488D01*
G01X275400Y602700D02*
X275100Y602400D01*
X270000D01*
G01X270521Y612019D02*
Y608859D01*
X271050Y608330D01*
Y605500D01*
G01X267550D02*
X263600D01*
X262500Y604400D01*
Y600100D01*
X265600Y597000D01*
X267600D01*
G01X224566Y658967D02*
Y655657D01*
X223509Y654600D01*
X220400D01*
G01X223544Y670886D02*
Y666135D01*
X220155Y662746D01*
Y654845D01*
X220400Y654600D01*
G01X214500Y626500D02*
X215800Y627800D01*
Y633848D01*
X211706Y637942D01*
G01X212900Y619201D02*
Y622200D01*
X213700Y623000D01*
Y625700D01*
X214500Y626500D01*
G01X211417Y597638D02*
X211418D01*
X212905Y596151D01*
X215188D01*
X216366Y594973D01*
Y593928D01*
X217156Y593138D01*
X218276D01*
X219626Y594488D01*
X220866D01*
G01X212991Y599212D02*
X211417Y597638D01*
G01X212992Y602363D02*
X214566Y603937D01*
X214567D01*
G01Y597638D02*
X216141Y599212D01*
G01X211417Y600787D02*
X214567D01*
G01X211417Y603937D02*
Y600787D01*
G01X216141Y599212D02*
X214567Y600786D01*
Y600787D01*
G01X266550Y643000D02*
Y641300D01*
X268850Y639000D01*
G01X266550Y643000D02*
Y651800D01*
X267250Y652500D01*
G01D02*
X269650Y654900D01*
X279050D01*
X286000Y661850D01*
Y671200D01*
X282600Y674600D01*
G01X220614Y616544D02*
X223807Y619737D01*
Y621743D01*
X221900Y623650D01*
G01X217716Y603937D02*
Y610100D01*
X219900Y612284D01*
Y615830D01*
X220614Y616544D01*
G01X221900Y623650D02*
X225900D01*
G01X234000Y622750D02*
X231800Y624950D01*
X229900D01*
G01X233300Y618300D02*
X234000Y619000D01*
Y622750D01*
G01X220866Y600787D02*
X221630Y601551D01*
Y602275D01*
X224200Y604845D01*
Y610500D01*
X230737Y617037D01*
X232037D01*
X233300Y618300D01*
G01X217716Y597638D02*
X219415Y599337D01*
X221467D01*
X222530Y600400D01*
Y601902D01*
X225464Y604836D01*
Y610491D01*
X230273Y615300D01*
X235404D01*
X238000Y617896D01*
G01X238250Y633200D02*
X240305Y631145D01*
Y625055D01*
X238000Y622750D01*
G01D02*
Y617896D01*
G01X209841Y592913D02*
X211416Y594488D01*
X211417D01*
G01X239850Y601000D02*
X237900D01*
X237000Y600100D01*
Y597400D01*
G01X226168Y618952D02*
Y614274D01*
X219166Y607272D01*
Y602237D01*
X217716Y600787D01*
G01X212993Y592912D02*
X214567Y594486D01*
Y594488D01*
G01X232130Y612950D02*
X231714Y612534D01*
X229376D01*
X226364Y609522D01*
Y604463D01*
X223430Y601529D01*
Y600027D01*
X221840Y598437D01*
X221665D01*
X220866Y597638D01*
G01X248215Y616637D02*
X248766D01*
X252272Y613131D01*
G01D02*
X251900Y612759D01*
Y609600D01*
G01X244156Y617237D02*
X247615D01*
X248215Y616637D01*
G01X244156Y613737D02*
X240300D01*
G01X244750Y652500D02*
X243950Y653300D01*
X240650D01*
X238950Y651600D01*
G01X247400Y642950D02*
X248441Y643991D01*
Y649159D01*
X253407Y654125D01*
X254811D01*
X257061Y656375D01*
X259750D01*
G01X243400Y642950D02*
X247400D01*
G01X238950Y651600D02*
X238800Y651450D01*
Y645450D01*
X241300Y642950D01*
X243400D01*
G01X261750Y643000D02*
Y641450D01*
X259777Y639477D01*
Y638873D01*
G01X242000Y656400D02*
X241650D01*
X238950Y659100D01*
G01X252250Y648625D02*
Y643656D01*
X252492Y643414D01*
G01X258250Y643000D02*
X252906D01*
X252492Y643414D01*
G01X255733Y622329D02*
X257629D01*
X259757Y624457D01*
Y626253D01*
G01X259646Y630071D02*
Y626364D01*
X259757Y626253D01*
G01X259823Y634343D02*
Y635035D01*
X263598Y638810D01*
X264683D01*
G01X259646Y630071D02*
Y634166D01*
X259823Y634343D01*
G01X273467Y657050D02*
X263750D01*
X261500Y659300D01*
X245250D01*
X241131Y663419D01*
X238936D01*
G01X274200Y663600D02*
Y657783D01*
X273467Y657050D01*
G01X248531Y692774D02*
Y699231D01*
X248600Y699300D01*
G01X249842Y707260D02*
X251998D01*
X253196Y706062D01*
G01X248600Y699300D02*
X249850Y700550D01*
Y703200D01*
X249842Y703208D01*
Y707260D01*
G01X217638Y688956D02*
Y695562D01*
G01X235000Y692900D02*
X236950Y690950D01*
Y676973D01*
X235659Y675682D01*
Y669954D01*
X230485Y664780D01*
X227880D01*
X224566Y661466D01*
Y658967D01*
G01X273800Y686350D02*
Y683000D01*
X277950Y678850D01*
Y676360D01*
X279510Y674800D01*
X282400D01*
X282600Y674600D01*
G01X259150Y666100D02*
Y669450D01*
X258800Y669800D01*
G01X258269Y662209D02*
Y665219D01*
X259150Y666100D01*
G01X252250Y662625D02*
X256137D01*
X256553Y662209D01*
X258269D01*
G01X262323Y716917D02*
X257358D01*
X256666Y716225D01*
G01X249842Y710760D02*
X251201D01*
X256666Y716225D01*
G01X270900Y674050D02*
Y679757D01*
X271240Y680097D01*
G01Y686350D02*
Y680097D01*
G01X270900Y674050D02*
X274250D01*
X276100Y675900D01*
Y677700D01*
G01X255200Y680950D02*
X256900Y679250D01*
X258500D01*
G01D02*
Y685945D01*
X258371Y686074D01*
G01X238936Y666919D02*
X237239D01*
X236110Y665790D01*
Y663080D01*
X238840Y660350D01*
Y659210D01*
X238950Y659100D01*
G01X244750Y666500D02*
X239355D01*
X238936Y666919D01*
G01X266300Y692574D02*
X263491D01*
G01D02*
Y695791D01*
X266649Y698949D01*
Y702151D01*
X265396Y703404D01*
Y708270D01*
X267350Y710224D01*
G01D02*
Y714507D01*
X263090Y718767D01*
X255586D01*
X250532Y713713D01*
X245249D01*
X229086Y697550D01*
X213450D01*
X209764Y693864D01*
Y688956D01*
G01X242900Y675650D02*
X241650D01*
X239400Y677900D01*
G01X244750Y666500D02*
Y673800D01*
X242900Y675650D01*
G01X251900Y679750D02*
Y681622D01*
X250998Y682524D01*
X246947D01*
X245971Y683500D01*
Y686274D01*
G01X247400Y679150D02*
X251300D01*
X251900Y679750D01*
G01X242900Y679150D02*
X247400D01*
G01X262400Y669800D02*
X264550D01*
X266800Y667550D01*
G01X274200Y663600D02*
X270750D01*
X266800Y667550D01*
G01X338743Y122894D02*
X355106D01*
X357560Y120440D01*
X360500D01*
G01X295841Y176793D02*
X297437D01*
X298340Y175890D01*
X299874D01*
X300777Y176793D01*
X321351D01*
X323422Y178864D01*
Y178904D01*
X323582Y179064D01*
G01X339851Y179467D02*
X344284D01*
X344388Y179571D01*
G01X314666Y192717D02*
X320031D01*
X322047Y190701D01*
Y188827D01*
X331407Y179467D01*
X339851D01*
G01X297146Y233661D02*
X302995D01*
X305782Y230874D01*
G01X340167Y231156D02*
X335500D01*
X335082Y231574D01*
G01X370522Y240684D02*
Y238722D01*
X367524Y235724D01*
X350824D01*
X347400Y232300D01*
Y225500D01*
X346500Y224600D01*
X327888D01*
X324262Y220974D01*
X323072D01*
X322301Y220203D01*
Y220009D01*
G01X338882Y248674D02*
Y254774D01*
X340232Y256124D01*
Y256474D01*
G01X314666Y243110D02*
X333318D01*
X338882Y248674D01*
G01X314666Y236811D02*
X336098D01*
X344311Y245024D01*
X352232D01*
X368105Y260897D01*
Y335605D01*
X372000Y339500D01*
Y363546D01*
X382677Y374223D01*
Y387323D01*
X380800Y389200D01*
Y433773D01*
X369873Y444700D01*
X354271D01*
X351880Y447091D01*
X351524D01*
X351523Y447090D01*
X301210D01*
X296400Y451900D01*
X289500D01*
G01X314666Y233661D02*
X337569D01*
X340500Y236592D01*
Y236600D01*
G01X297146Y246260D02*
X303426D01*
X305225Y244461D01*
X305454D01*
G01X340209Y261112D02*
Y260731D01*
X334998Y255520D01*
G01X314666Y258858D02*
X326438D01*
X332753Y265173D01*
X334111D01*
X337523Y268585D01*
X338751D01*
G01X314666Y262008D02*
X326759D01*
X331924Y267173D01*
X333278D01*
X339182Y273077D01*
G01X297146Y252559D02*
X303915D01*
X305373Y251101D01*
G01X297146Y255709D02*
X305042D01*
X306412Y254339D01*
G01X338982Y243274D02*
X343022Y247314D01*
X345672D01*
G01X314666Y239961D02*
X335669D01*
X338982Y243274D01*
G01X297146Y236811D02*
X303345D01*
X305882Y234274D01*
G01X297146Y239961D02*
X303584D01*
X305772Y237773D01*
Y237673D01*
G01X314666Y246260D02*
X321440D01*
X321700Y246000D01*
G01X314666Y249410D02*
X321010D01*
X321600Y250000D01*
G01X297146Y243110D02*
X303747D01*
X305781Y241076D01*
G01X328913Y274414D02*
X333859D01*
X339456Y280011D01*
Y281150D01*
X341100Y282794D01*
Y390250D01*
X344732Y393882D01*
G01X334017Y272000D02*
Y272450D01*
X340957Y279390D01*
Y280529D01*
X342600Y282172D01*
Y388142D01*
X344732Y390274D01*
G01X342744Y268585D02*
X338751D01*
G01X339182Y273077D02*
X339353Y272906D01*
X343041D01*
G01X335800Y379800D02*
X335850D01*
X335900Y379750D01*
Y372000D01*
X338755Y369145D01*
Y289656D01*
X337808Y288709D01*
G01X297146Y378543D02*
X301251D01*
X303680Y380972D01*
G01X289500Y451900D02*
X282800D01*
X281200Y453500D01*
G01X350400Y459000D02*
X340300Y469100D01*
Y492268D01*
X337600Y494968D01*
G01X336600Y504500D02*
X334800Y502700D01*
Y497768D01*
X337600Y494968D01*
G01X343000Y492100D02*
Y493000D01*
X336800Y499200D01*
Y499967D01*
G01X327071Y526309D02*
X323374D01*
X322382Y527301D01*
X321173D01*
X320903Y527571D01*
X317870D01*
G01X327071Y526309D02*
X324000Y529380D01*
X322889D01*
G01X305070Y522451D02*
X310635D01*
X315620Y517466D01*
X338418D01*
X340789Y519837D01*
X340937D01*
X341500Y520400D01*
G01X318778Y510778D02*
X324478D01*
X327200Y513500D01*
X334622D01*
X339272Y508850D01*
X341496D01*
X344066Y511420D01*
Y513753D01*
X344900Y514587D01*
X347372D01*
X350843Y518058D01*
X364219D01*
X366500Y520339D01*
Y546785D01*
X363935Y549350D01*
X361033D01*
X360274Y550109D01*
X355739D01*
G01X318778Y510778D02*
X299970D01*
X299448Y511300D01*
G01X332821Y515415D02*
X332636Y515600D01*
X301620D01*
G01X305070Y527571D02*
X297063D01*
X296192Y526700D01*
X292886D01*
X291183Y524997D01*
X287615D01*
G01X340800Y504200D02*
X336100Y508900D01*
X334650D01*
G01X294905Y546906D02*
X300475D01*
X300476Y546907D01*
G01X281645Y546834D02*
X286408D01*
X287271Y545971D01*
G01X291405Y546906D02*
X290470Y545971D01*
X287271D01*
G01X281645Y551954D02*
X285354D01*
X286700Y553300D01*
X287200D01*
G01D02*
X287900D01*
X289900Y551300D01*
X291450D01*
G01X291800Y576708D02*
Y575250D01*
X293350Y573700D01*
G01X329840Y572710D02*
Y573250D01*
X331257Y574667D01*
X336021D01*
G01X298982Y578108D02*
X295824D01*
G01X336021Y577227D02*
X329884D01*
X325475Y572818D01*
G01X333512Y553888D02*
X338288D01*
X340200Y555800D01*
Y558500D01*
X339393Y559307D01*
X336021D01*
G01Y561867D02*
X340602D01*
X342200Y560269D01*
Y554962D01*
X337196Y549958D01*
X336382D01*
X336367Y549943D01*
G01X299426Y557611D02*
X297258D01*
X294107Y560762D01*
G01X336021Y564427D02*
X332861D01*
X330729Y562295D01*
Y557268D01*
G01X299150Y564200D02*
Y562150D01*
X298000Y561000D01*
G01X336021Y566987D02*
X332705D01*
X332318Y566600D01*
X330405D01*
X327059Y563254D01*
Y557247D01*
G01X291650Y565600D02*
X289176D01*
X288309Y566467D01*
G01X328580Y568120D02*
X329060Y568600D01*
X331489D01*
X332436Y569547D01*
X336021D01*
G01X291000Y570810D02*
X291110D01*
X292220Y569700D01*
X294050D01*
G01X320954Y572631D02*
X322725Y570860D01*
X330920D01*
X332167Y572107D01*
X336021D01*
G01X313821Y577227D02*
X309127D01*
X306364Y574464D01*
G01D02*
X305307Y575521D01*
X298671D01*
X296850Y573700D01*
G01X307519Y584195D02*
X311005D01*
X313821Y581379D01*
Y579787D01*
G01X302482Y578108D02*
X304738D01*
X306251Y579621D01*
Y582927D01*
X307519Y584195D01*
G01X319529Y562413D02*
X318983Y561867D01*
X313821D01*
G01Y564427D02*
X317170D01*
X319252Y566509D01*
G01X307385Y559544D02*
X309401Y561560D01*
Y565266D01*
X311122Y566987D01*
X313821D01*
G01X302926Y557611D02*
X305452D01*
X307385Y559544D01*
G01X313821Y569547D02*
X310668D01*
X307187Y566066D01*
G01X302650Y564200D02*
X305321D01*
X307187Y566066D01*
G01X303091Y568720D02*
X303445Y569074D01*
X307193D01*
X310226Y572107D01*
X313821D01*
G01X303091Y568720D02*
X301471Y567100D01*
X296650D01*
X295150Y565600D01*
G01X297550Y569700D02*
Y571043D01*
X299728Y573221D01*
X301365D01*
G01X313821Y574667D02*
X309608D01*
X306741Y571800D01*
X302786D01*
X301365Y573221D01*
G01X285912Y538750D02*
X289050D01*
G01D02*
X293150D01*
G01D02*
X293500D01*
X294250Y539500D01*
Y543000D01*
G01D02*
X295968D01*
X297986Y545018D01*
X301204D01*
X302511Y546325D01*
X306052D01*
G01X317870Y530131D02*
X320811D01*
X322060Y531380D01*
X326730D01*
G01D02*
X324856Y533254D01*
X322843D01*
G01X349334Y557789D02*
X346190Y554645D01*
Y552433D01*
X344846Y551089D01*
X341317D01*
X337977Y547749D01*
X336590D01*
X332834Y543993D01*
G01X337346Y545100D02*
X337450D01*
X341745Y549395D01*
X345274D01*
X351108Y555229D01*
X355739D01*
G01X277750Y575000D02*
X280500Y577750D01*
Y582000D01*
X282000Y583500D01*
G01X294950Y551300D02*
X295754D01*
X296167Y550887D01*
X297811D01*
X298514Y550184D01*
G01X327250Y586940D02*
X324855D01*
X324009Y587786D01*
Y593513D01*
X317689Y599833D01*
G01X313821Y559307D02*
X317609D01*
X319430Y557486D01*
G01X305070Y530131D02*
X298308D01*
G01X277441Y539882D02*
X277453Y539870D01*
X280146D01*
X281158Y538858D01*
G01X289050Y535250D02*
X284766D01*
X281158Y538858D01*
G01X309417Y589500D02*
X314181D01*
G01X309417D02*
X304950D01*
X304300Y590150D01*
G01X314181Y589500D02*
X320750D01*
G01X323956Y539616D02*
X322575D01*
X319806Y542385D01*
X315252D01*
G01X328659Y539609D02*
X323963D01*
X323956Y539616D01*
G01X332415Y539609D02*
X328659D01*
G01X299294Y542868D02*
X299937Y543511D01*
X301989D01*
X302833Y544355D01*
X306052D01*
G01X297175Y538504D02*
Y540749D01*
X299294Y542868D01*
G01X326266Y543816D02*
X325727Y544355D01*
X322511D01*
G01D02*
X315252D01*
G01X316083Y535357D02*
X319725D01*
X320031Y535663D01*
G01D02*
X321114Y536746D01*
Y538848D01*
X319547Y540415D01*
X315252D01*
G01X301216Y535004D02*
X303073D01*
X303425Y535356D01*
X305001D01*
G01X301216Y535004D02*
X297175D01*
G01X306052Y542385D02*
X302985D01*
X300068Y539468D01*
Y537897D01*
X297175Y535004D01*
G01X308501Y535356D02*
X312582D01*
X312583Y535357D01*
G01X310292Y532128D02*
X308501Y533919D01*
Y535356D01*
G01X300200Y593650D02*
Y596400D01*
X299200Y597400D01*
G01D02*
X295650D01*
X295250Y597000D01*
X287600D01*
G01X279745Y618515D02*
X286035D01*
X287550Y617000D01*
G01X305100Y658050D02*
X302350Y660800D01*
Y662996D01*
X301054Y664292D01*
Y666724D01*
G01X299900Y657300D02*
X304350D01*
X305100Y658050D01*
G01X303741Y648343D02*
Y651409D01*
X299900Y655250D01*
Y657300D01*
G01X327561Y656480D02*
Y657646D01*
X330515Y660600D01*
X336855D01*
X341355Y665100D01*
X343400D01*
X344445Y664055D01*
X346881D01*
G01X304300Y593650D02*
X307703D01*
X308200Y593153D01*
G01X283200Y663600D02*
Y668300D01*
X281300Y670200D01*
G01X275300Y668749D02*
X276944Y670393D01*
X281107D01*
X281300Y670200D01*
G01X276800Y697925D02*
Y697900D01*
X276360Y697460D01*
Y692850D01*
G01X339731Y682730D02*
Y680091D01*
X339800Y680022D01*
Y679034D01*
X339804Y679030D01*
G01X339731Y682730D02*
Y690518D01*
X338669Y691580D01*
G01X336200Y677000D02*
Y676670D01*
X331580Y672050D01*
X331319D01*
X329119Y669850D01*
X328000D01*
G01D02*
Y667416D01*
X331436Y663980D01*
G01X352410Y685260D02*
X355764D01*
X356608Y686104D01*
Y696219D01*
X355216Y697611D01*
X347139D01*
X347041Y697709D01*
X345461D01*
X341920Y701250D01*
X339533D01*
X338450Y702333D01*
Y703150D01*
X335749Y705852D01*
Y711008D01*
X324559Y722198D01*
Y727730D01*
X316382Y735907D01*
X313873D01*
G01X314100Y739300D02*
X315493Y737907D01*
X317211D01*
X326559Y728559D01*
Y723027D01*
X337749Y711837D01*
Y708251D01*
X341050Y704950D01*
X341067D01*
X342150Y703867D01*
Y703849D01*
X346290Y699709D01*
X346998D01*
X346999Y699710D01*
X356480D01*
X358986Y697204D01*
Y685118D01*
X356568Y682700D01*
X352410D01*
G01X301054Y666724D02*
Y669346D01*
X300100Y670300D01*
G01X340583Y670807D02*
X337840Y673550D01*
X336500D01*
G01X371518Y49223D02*
X368664D01*
X362848Y55039D01*
X353543D01*
G01X371518Y49223D02*
Y46253D01*
X370870Y45605D01*
G01X371518Y53823D02*
X367687D01*
X362508Y59002D01*
X357454D01*
X353543Y62913D01*
G01X371518Y53823D02*
Y54300D01*
X368059Y57759D01*
G01X342539Y120370D02*
X342609Y120440D01*
X351500D01*
G01X371344Y84695D02*
Y86642D01*
X369253Y88733D01*
G01X353543Y86535D02*
X353828D01*
X356010Y84353D01*
X371002D01*
X371344Y84695D01*
G01X353543Y78661D02*
X355325Y80443D01*
X370996D01*
X371344Y80095D01*
G01D02*
Y77637D01*
X370825Y77118D01*
X367287D01*
G01X381269Y94981D02*
Y93626D01*
X384769Y90126D01*
Y87102D01*
X388527Y83344D01*
X391551D01*
X408382Y66513D01*
X457839D01*
X474106Y82780D01*
X479147D01*
X484229Y87862D01*
X559362D01*
X559900Y88400D01*
G01X563268Y88872D02*
X561739Y90401D01*
X559072D01*
X558533Y89862D01*
X483400D01*
X478318Y84780D01*
X473277D01*
X457010Y68513D01*
X409211D01*
X392380Y85344D01*
X389356D01*
X386769Y87931D01*
Y91638D01*
X384666Y93741D01*
G01X419662Y71426D02*
X417075Y74013D01*
X412481D01*
X383678Y102816D01*
Y161140D01*
X387202Y164664D01*
G01X423340Y71621D02*
X418948Y76013D01*
X413606D01*
X385678Y103941D01*
Y160311D01*
X386226Y160859D01*
X387393D01*
G01X469653Y88700D02*
X457551Y76598D01*
X424128D01*
X420713Y80013D01*
X415897D01*
X391503Y104407D01*
Y166513D01*
X387628Y170388D01*
Y365351D01*
X390677Y368400D01*
Y448523D01*
X380971Y458229D01*
Y463642D01*
X390400Y473071D01*
Y476241D01*
X387259Y479382D01*
Y495201D01*
X392358Y500300D01*
Y502289D01*
X394082Y504013D01*
Y530793D01*
X397617Y534328D01*
Y564217D01*
X401012Y567612D01*
Y567662D01*
X401013Y567663D01*
Y569319D01*
X401012Y569320D01*
Y646951D01*
X396650Y651313D01*
Y676404D01*
X392105Y680949D01*
Y684644D01*
G01X475310Y89843D02*
X460065Y74598D01*
X423299D01*
X419884Y78013D01*
X415068D01*
X389503Y103578D01*
Y165286D01*
X385628Y169161D01*
Y366180D01*
X388677Y369229D01*
Y447694D01*
X378971Y457400D01*
Y464471D01*
X388400Y473900D01*
Y475412D01*
X385259Y478553D01*
Y496030D01*
X390357Y501128D01*
Y503117D01*
X392082Y504842D01*
Y531622D01*
X395617Y535157D01*
Y565096D01*
X399012Y568491D01*
Y646122D01*
X394650Y650484D01*
Y675177D01*
X394150Y675677D01*
X391873D01*
X389650Y677900D01*
G01X456430Y87000D02*
X452028Y82598D01*
X426615D01*
X423200Y86013D01*
X418385D01*
X397503Y106895D01*
Y165714D01*
X400340Y168551D01*
Y176118D01*
X393646Y182812D01*
Y347207D01*
X393628Y347225D01*
Y362278D01*
X396677Y365327D01*
Y475717D01*
X393571Y478823D01*
Y485666D01*
X392109Y487128D01*
Y494393D01*
X396358Y498642D01*
Y500631D01*
X398082Y502355D01*
Y529135D01*
X399614Y530667D01*
X401394D01*
X405016Y534289D01*
Y697427D01*
X399093Y703350D01*
G01X399154Y699950D02*
X403016Y696088D01*
Y535118D01*
X400565Y532667D01*
X398785D01*
X396082Y529964D01*
Y503184D01*
X394358Y501460D01*
Y499471D01*
X390109Y495222D01*
Y486299D01*
X391570Y484838D01*
Y479920D01*
X391571Y479919D01*
Y477994D01*
X394677Y474888D01*
Y366156D01*
X391628Y363107D01*
Y346396D01*
X391646Y346378D01*
Y181983D01*
X398340Y175289D01*
Y169380D01*
X395503Y166543D01*
Y106065D01*
X417555Y84013D01*
X422371D01*
X425786Y80598D01*
X454469D01*
X461200Y87329D01*
Y96200D01*
X466423Y101423D01*
Y162317D01*
X464173Y164567D01*
G01X390999Y461382D02*
Y451500D01*
X392677Y449822D01*
Y367571D01*
X389628Y364522D01*
Y345567D01*
X389646Y345549D01*
Y171674D01*
X393503Y167817D01*
Y105236D01*
X416726Y82013D01*
X421542D01*
X424957Y78598D01*
X455568D01*
X463700Y86730D01*
Y93101D01*
X470461Y99862D01*
X527683D01*
X535230Y107409D01*
Y114370D01*
X532789Y116811D01*
Y170979D01*
X535039Y173229D01*
G01X395928Y482925D02*
Y479333D01*
X398677Y476584D01*
Y184409D01*
X407636Y175450D01*
Y109517D01*
X413553Y103600D01*
X425894D01*
X438077Y115783D01*
Y156805D01*
X435827Y159055D01*
G01X383285Y347114D02*
X380644Y344473D01*
Y334348D01*
X378118Y331822D01*
Y169894D01*
X375561Y167337D01*
X370149D01*
G01X370882Y163688D02*
X372291Y165097D01*
X376150D01*
X380118Y169065D01*
Y330993D01*
X383327Y334202D01*
Y343379D01*
G01X400080Y491107D02*
X404677Y486510D01*
Y186896D01*
X413636Y177937D01*
Y112004D01*
X416040Y109600D01*
X423407D01*
X424990Y111183D01*
Y164754D01*
X428740Y168504D01*
G01X400080Y523903D02*
X402943Y521040D01*
Y499569D01*
X396109Y492735D01*
Y488786D01*
X400677Y484218D01*
Y185238D01*
X409636Y176279D01*
Y110346D01*
X414382Y105600D01*
X425065D01*
X432990Y113525D01*
Y170392D01*
X435827Y173229D01*
G01X400080Y528243D02*
X404943Y523380D01*
Y498740D01*
X398109Y491906D01*
Y489615D01*
X402677Y485047D01*
Y186067D01*
X411636Y177108D01*
Y111175D01*
X415211Y107600D01*
X424236D01*
X430990Y114354D01*
Y173903D01*
X435827Y178740D01*
G01X370682Y192824D02*
Y192155D01*
X374014Y188823D01*
G01D02*
Y186344D01*
X367476Y179806D01*
G01X353972Y186944D02*
X352843Y185815D01*
Y182663D01*
X353762Y181744D01*
G01X359976Y183681D02*
Y193737D01*
X362484Y196245D01*
Y196669D01*
G01D02*
X358305D01*
X356611Y198363D01*
Y200364D01*
G01X353762Y181744D02*
X358039D01*
X359976Y183681D01*
G01X349004Y179580D02*
X344397D01*
X344388Y179571D01*
G01X366792Y224934D02*
X365353D01*
X364572Y225715D01*
X361105D01*
X358847Y223457D01*
Y209614D01*
X362900Y205561D01*
Y203774D01*
X364622Y202052D01*
Y195440D01*
X362727Y193545D01*
Y192756D01*
G01X367476Y187556D02*
Y192010D01*
X366632Y192854D01*
G01X362727Y192756D02*
Y188984D01*
X364155Y187556D01*
X367476D01*
G01X365100Y348300D02*
X360500Y343700D01*
Y264492D01*
X350782Y254774D01*
X347482D01*
G01X383140Y367158D02*
X376300Y360318D01*
Y336500D01*
X372267Y332467D01*
Y257139D01*
X353928Y238800D01*
X347900D01*
X343667Y234567D01*
Y231156D01*
G01X343697Y226992D02*
Y231126D01*
X343667Y231156D01*
G01X370422Y245284D02*
Y240784D01*
X370522Y240684D01*
G01X369095Y217923D02*
X374618Y223446D01*
Y243393D01*
X372267Y245744D01*
X370882D01*
X370422Y245284D01*
G01X363975Y211423D02*
X361831D01*
X360347Y212907D01*
Y222835D01*
X361726Y224214D01*
X363562D01*
X365202Y222574D01*
X368662D01*
X370292Y224204D01*
Y224934D01*
G01D02*
X368412Y226814D01*
Y232724D01*
G01X343732Y256474D02*
X346565D01*
X346715Y256624D01*
X349132D01*
X358877Y266369D01*
Y357277D01*
X360446Y358846D01*
G01X349081Y242261D02*
X352769D01*
X370106Y259598D01*
Y333506D01*
X374200Y337600D01*
Y362917D01*
X384677Y373394D01*
Y390489D01*
X383900Y391266D01*
Y422100D01*
G01X340500Y236600D02*
X340508D01*
X345581Y241673D01*
Y242261D01*
G01X352017Y263432D02*
X349697Y261112D01*
X343709D01*
G01X349172Y247314D02*
X351693D01*
X366104Y261725D01*
Y337504D01*
X369300Y340700D01*
Y362600D01*
G01X383030Y352442D02*
X378644Y348056D01*
Y335177D01*
X376118Y332651D01*
Y219218D01*
X371500Y214600D01*
X367200D01*
X366535Y215265D01*
Y217923D01*
G01X354572Y232724D02*
X355112D01*
X358632Y229204D01*
X364502D01*
X366792Y226914D01*
Y224934D01*
G01X342885Y276301D02*
X343294D01*
X346877Y279884D01*
Y374723D01*
X346600Y375000D01*
G01X342958Y279701D02*
X344600Y281343D01*
Y376600D01*
X347800Y379800D01*
Y383806D01*
X344732Y386874D01*
G01X346244Y268585D02*
X347171D01*
X350877Y272291D01*
Y369311D01*
X361176Y379610D01*
G01X346541Y272906D02*
X348877Y275242D01*
Y370389D01*
X354850Y376362D01*
G01X378492Y378175D02*
Y376892D01*
X360446Y358846D01*
G01X352700Y498400D02*
X349200Y494900D01*
Y475200D01*
X359100Y465300D01*
Y462000D01*
X367250Y453850D01*
X370250D01*
X372000Y452100D01*
G01X369900Y458700D02*
X369500Y459100D01*
X365900D01*
X361600Y463400D01*
Y469200D01*
X360400Y470400D01*
G01X376700Y480300D02*
Y467300D01*
X371600Y462200D01*
X368400D01*
X367400Y461200D01*
G01X390999Y461382D02*
Y463451D01*
X387450Y467000D01*
G01X352700Y498400D02*
X355300Y501000D01*
Y502700D01*
G01X360400Y470400D02*
X358657D01*
X351700Y477357D01*
Y491880D01*
X357700Y497880D01*
Y499000D01*
G01X395928Y482925D02*
Y486138D01*
X394109Y487957D01*
Y493564D01*
X400080Y499535D01*
Y500854D01*
G01X384849Y525499D02*
X383667Y526681D01*
X379088D01*
G01X384849Y521681D02*
X379088D01*
G01X355300Y506100D02*
X357099Y507899D01*
X361439D01*
G01X355300Y513500D02*
X356961Y511839D01*
X361439D01*
G01X354440Y485780D02*
X356500D01*
X359337Y488617D01*
X362417D01*
X364200Y490400D01*
X376077D01*
X377644Y491967D01*
G01X354440Y485780D02*
Y481710D01*
X354580Y481570D01*
G01X377644Y491967D02*
Y494106D01*
X376417Y495333D01*
Y497796D01*
X381489Y502868D01*
Y506845D01*
X380435Y507899D01*
X377739D01*
G01Y511839D02*
X372892D01*
X370855Y513876D01*
Y530019D01*
X369031Y531843D01*
Y542431D01*
X369500Y542900D01*
G01X386367Y474700D02*
X385576D01*
X382759Y477517D01*
Y497066D01*
X386730Y501037D01*
Y503107D01*
X386729Y503108D01*
Y511755D01*
X387452Y512478D01*
X387453D01*
X388908Y513933D01*
Y531985D01*
X390371Y533448D01*
X390372D01*
X391150Y534226D01*
Y547238D01*
X388641Y549747D01*
G01X343000Y492100D02*
Y469800D01*
X350400Y462400D01*
G01X345428Y517086D02*
X345500Y517158D01*
Y518600D01*
X344700Y519400D01*
Y522600D01*
G01X359088Y526681D02*
X357431D01*
X355200Y524450D01*
X350000D01*
G01D02*
X346550D01*
X344700Y522600D01*
G01X373699Y521160D02*
X373963D01*
X375682Y519441D01*
X381365D01*
X384229Y516577D01*
Y502072D01*
X380259Y498102D01*
Y484330D01*
X376700Y480771D01*
Y480300D01*
G01X377739Y505934D02*
X371793D01*
X369059Y503200D01*
X359100D01*
G01X374800Y516912D02*
X375652D01*
X377739Y514825D01*
Y513804D01*
G01X363553Y476212D02*
X360588D01*
X358800Y478000D01*
G01X368900Y487050D02*
Y480348D01*
X368543Y479991D01*
G01X363553Y479712D02*
X368264D01*
X368543Y479991D01*
G01X366340Y487050D02*
X365407Y486117D01*
X360374D01*
G01D02*
X358080Y483823D01*
Y481570D01*
G01X371460Y493550D02*
Y500807D01*
X372563Y501910D01*
X372710D01*
X373800Y503000D01*
G01X347750Y503600D02*
X346800Y502650D01*
X342350D01*
X340800Y504200D01*
G01X351311Y507831D02*
Y503661D01*
X351250Y503600D01*
G01Y511900D02*
Y507892D01*
X351311Y507831D01*
G01X352490Y515908D02*
Y515890D01*
X351250Y514650D01*
Y511900D01*
G01X361439Y513804D02*
X359272D01*
X356976Y516100D01*
X352700D01*
X352508Y515908D01*
X352490D01*
G01X361439Y505934D02*
X364934D01*
X365600Y506600D01*
Y512700D01*
X364496Y513804D01*
X361439D01*
G01X351250Y503600D02*
Y502458D01*
X349088Y500296D01*
G01X379088Y531681D02*
X381331D01*
X385600Y535950D01*
G01X387561Y540889D02*
Y537911D01*
X385600Y535950D01*
G01X364014Y593996D02*
Y593756D01*
X360820Y590562D01*
Y590286D01*
G01X363195Y601320D02*
Y595795D01*
X360800Y593400D01*
X359400D01*
X356680Y590680D01*
Y589114D01*
G01D02*
X359648D01*
X360820Y590286D01*
G01X368500Y591900D02*
Y592366D01*
X365164Y595702D01*
Y601320D01*
G01X369969Y586558D02*
Y590431D01*
X368500Y591900D01*
G01X352480Y589614D02*
X353485D01*
X355400Y591529D01*
Y593400D01*
G01X352480Y589614D02*
X348636D01*
X346303Y591947D01*
G01X372700Y593600D02*
X372800Y593500D01*
Y588342D01*
X374292Y586850D01*
G01X378350Y584856D02*
X376286D01*
X374292Y586850D01*
G01X379628Y589070D02*
X380830D01*
X382700Y587200D01*
X384872D01*
X386529Y585543D01*
G01X377700Y595000D02*
Y593030D01*
X379600Y591130D01*
Y589098D01*
X379628Y589070D01*
G01X382550Y584856D02*
X380587Y586819D01*
X378838D01*
X375771Y589886D01*
Y590734D01*
G01D02*
Y593629D01*
X371070Y598330D01*
Y601320D01*
G01X387550Y589571D02*
X384492Y589500D01*
X383622Y590370D01*
G01D02*
X379848Y594144D01*
Y597844D01*
X376814Y600878D01*
Y604746D01*
G01X377939Y547549D02*
X382837D01*
X383229Y547941D01*
X384746D01*
G01D02*
X386723Y545964D01*
Y544565D01*
G01X355739Y575709D02*
X351391D01*
X349700Y577400D01*
G01X345900Y578050D02*
X349050D01*
X349700Y577400D01*
G01X386250Y568500D02*
Y564573D01*
X386835Y563988D01*
G01X377939Y568029D02*
X383912D01*
X384383Y568500D01*
X386250D01*
G01X386835Y563988D02*
X387173Y563650D01*
X391549D01*
G01X342440Y571770D02*
X344041Y570169D01*
X350816D01*
X351989Y571342D01*
Y571600D01*
X353538Y573149D01*
X355739D01*
G01X361900Y570800D02*
X361689Y570589D01*
X355739D01*
G01X345287Y541009D02*
X345250Y541046D01*
Y545100D01*
G01X345287Y541009D02*
X349615Y536681D01*
X351030D01*
G01D02*
X359088D01*
G01Y531681D02*
X353917D01*
X353148Y532450D01*
X350000D01*
G01X345443Y531460D02*
X346433Y532450D01*
X350000D01*
G01X340942Y528476D02*
X342459D01*
X345443Y531460D01*
G01X362300Y555200D02*
X363500D01*
X373769Y565469D01*
X377939D01*
G01Y570589D02*
X384339D01*
X386250Y572500D01*
G01X377939Y573149D02*
X382899D01*
X386250Y576500D01*
G01X355739Y568029D02*
X345429D01*
X343840Y566440D01*
G01X348300Y565400D02*
X348369Y565469D01*
X355739D01*
G01Y562909D02*
X359709D01*
X367004Y570204D01*
Y575840D01*
X365270Y577574D01*
Y580800D01*
G01X364900Y585171D02*
X364905D01*
X365270Y584806D01*
Y580800D01*
G01X364964Y588771D02*
X367499Y586236D01*
Y577467D01*
X368504Y576462D01*
Y568904D01*
X364551Y564951D01*
X364409D01*
X363326Y563868D01*
Y563726D01*
X359949Y560349D01*
X355739D01*
G01Y557789D02*
X349334D01*
G01X355739Y552669D02*
X352468D01*
X349005Y549206D01*
G01D02*
X347199Y547400D01*
X343200D01*
X341316Y545516D01*
Y545000D01*
G01X377939Y550109D02*
X375509D01*
X373659Y548259D01*
Y543497D01*
X371531Y541369D01*
Y537629D01*
X373222Y535938D01*
G01X377939Y552669D02*
X374008D01*
X372159Y550820D01*
Y548064D01*
X370313Y546218D01*
X370247D01*
G01X370223Y549965D02*
Y552000D01*
X373452Y555229D01*
X377939D01*
G01X384950Y551876D02*
X382285Y554541D01*
Y556757D01*
X381253Y557789D01*
X377939D01*
G01X384950Y555276D02*
Y556491D01*
X381092Y560349D01*
X377939D01*
G01X383056Y563675D02*
X382290Y562909D01*
X377939D01*
G01X389750Y572500D02*
X393311D01*
X393912Y571899D01*
G01X389750Y576500D02*
X392715D01*
X393910Y575305D01*
G01X387650Y610300D02*
Y613120D01*
X385845Y614925D01*
G01X387650Y606200D02*
Y610300D01*
G01X385845Y614925D02*
X384842D01*
X383998Y614081D01*
X380752D01*
X380244Y614589D01*
X376464D01*
G01X381967Y616123D02*
X380129D01*
X379695Y616557D01*
X376464D01*
G01X381967Y616123D02*
X383824Y617980D01*
X385965D01*
X387686Y619701D01*
G01X361227Y630300D02*
Y623920D01*
G01X352980Y636114D02*
Y635814D01*
X357094Y631700D01*
X359827D01*
X361227Y630300D01*
G01X359258Y623920D02*
Y626113D01*
X355471Y629900D01*
X351199D01*
X348600Y632499D01*
Y635550D01*
G01X355400Y593400D02*
X356900Y594900D01*
X360178D01*
X361227Y595949D01*
Y601320D01*
G01X372700Y593600D02*
X369101Y597199D01*
Y601320D01*
G01X377700Y595000D02*
Y597600D01*
X374330Y600970D01*
X373038D01*
G01X383127Y595147D02*
X381644Y596630D01*
Y598418D01*
X380621Y599441D01*
Y604772D01*
X378679Y606714D01*
X376464D01*
G01X387733Y594540D02*
X383734D01*
X383127Y595147D01*
G01X387733Y594540D02*
X392033D01*
X392133Y594440D01*
G01X363195Y623920D02*
Y634519D01*
X362614Y635100D01*
Y635920D01*
G01D02*
Y639802D01*
X362536Y639880D01*
G01D02*
Y643384D01*
X360049Y645871D01*
G01X365164Y623920D02*
Y632764D01*
X366114Y633714D01*
Y635920D01*
G01D02*
X366662Y636468D01*
Y639818D01*
X366664Y639820D01*
G01D02*
Y641649D01*
X365614Y642699D01*
Y650624D01*
X366817Y651827D01*
X369273D01*
G01X387650Y602100D02*
X386171D01*
X383271Y605000D01*
G01D02*
X379588Y608683D01*
X376464D01*
G01X383199Y623168D02*
X381469D01*
X380658Y622357D01*
Y619536D01*
X379648Y618526D01*
X376464D01*
G01X387731Y623786D02*
X383817D01*
X383199Y623168D01*
G01X388300Y632700D02*
X387202Y631602D01*
X384498D01*
X381273Y628377D01*
X379555D01*
X375448Y624270D01*
X373038D01*
G01X388300Y632700D02*
Y636548D01*
X387500Y637348D01*
G01X383168Y626894D02*
X381912D01*
X381895Y626877D01*
X380177D01*
X376814Y623514D01*
Y620494D01*
G01X383168Y626894D02*
X384355Y628081D01*
X387536D01*
G01X382438Y608755D02*
X380542Y610651D01*
X376464D01*
G01X384300Y619925D02*
X386021Y621646D01*
X389091D01*
X391231Y623786D01*
G01X341934Y662794D02*
Y660923D01*
X343006Y659851D01*
Y656555D01*
G01X346485Y676801D02*
X349323Y679639D01*
Y679640D01*
X349823Y680140D01*
X352410D01*
G01X343338Y679236D02*
X345773Y676801D01*
X346485D01*
G01X392500Y673500D02*
X390800Y671800D01*
X389150D01*
G01X374610Y682700D02*
X382530D01*
X383885Y684055D01*
G01X388605Y684644D02*
X384474D01*
X383885Y684055D01*
G01X374610Y680140D02*
X380660D01*
X381888Y678912D01*
G01D02*
X382900Y677900D01*
X386150D01*
G01X385650Y671800D02*
X382500D01*
X381377Y672923D01*
G01D02*
X380200Y674100D01*
Y676380D01*
X379000Y677580D01*
X374610D01*
G01X346881Y664055D02*
Y667019D01*
X343093Y670807D01*
X340583D01*
G01X360500Y709940D02*
X357108D01*
X355298Y711750D01*
G01X388675Y693371D02*
X391629D01*
X392500Y692500D01*
G01X374610Y692940D02*
X380900D01*
G01D02*
X384744D01*
X385175Y693371D01*
G01X458250Y30479D02*
X455500D01*
X453021Y28000D01*
X451500D01*
G01X446135Y30457D02*
X448592Y28000D01*
X451500D01*
G01X457950Y28510D02*
Y25750D01*
X455200Y23000D01*
X451800D01*
G01X446135Y26157D02*
X447243D01*
X450400Y23000D01*
X451800D01*
G01X458972Y49634D02*
X459000Y49606D01*
Y49000D01*
X461110Y46890D01*
Y45450D01*
G01X468200Y62550D02*
Y58400D01*
X467800Y58000D01*
G01X468266Y53745D02*
Y51566D01*
X467016Y50316D01*
Y45150D01*
G01X467800Y58000D02*
Y55880D01*
X468266Y55414D01*
Y53745D01*
G01X468200Y66050D02*
Y68848D01*
X470599Y71247D01*
G01X462625Y49881D02*
X463079Y49427D01*
Y45150D01*
G01X467300Y20000D02*
Y21850D01*
X467016Y22134D01*
Y25650D01*
G01X458250Y38353D02*
X454018D01*
X450020Y42351D01*
X448859D01*
G01D02*
X444754D01*
G01X440300Y42657D02*
X437635Y39992D01*
Y38057D01*
G01X440300Y42657D02*
X444448D01*
X444754Y42351D01*
G01X450454Y38147D02*
X452217Y36384D01*
X458250D01*
G01X446066Y38147D02*
X450454D01*
G01X444722Y53465D02*
X449768D01*
X452293Y50940D01*
G01X440300Y52457D02*
Y56716D01*
X440531Y56947D01*
G01X444722Y53465D02*
X441240Y56947D01*
X440531D01*
G01X452293Y50940D02*
X457950Y45283D01*
Y42290D01*
G01X446035Y21957D02*
X449191Y18801D01*
X460024D01*
G01D02*
X461110Y19887D01*
Y25350D01*
G01X458250Y34416D02*
X455716D01*
X454600Y33300D01*
X450900D01*
G01X446085Y34357D02*
X449843D01*
X450900Y33300D01*
G01X448520Y49979D02*
X448506Y49965D01*
X444722D01*
G01X440300Y47557D02*
Y47901D01*
X442364Y49965D01*
X444722D01*
G01X444754Y45851D02*
X445073Y45532D01*
X451196D01*
X456407Y40321D01*
X458250D01*
G01X444754Y45851D02*
X442006D01*
X440300Y47557D01*
G01X528950Y53600D02*
X522550Y60000D01*
X515901D01*
X495851Y80050D01*
X484197D01*
X481427Y77280D01*
X476632D01*
X470599Y71247D01*
G01X438600Y91033D02*
Y102500D01*
X445163Y109063D01*
Y153337D01*
X444169Y154331D01*
X442913D01*
G01X549212Y173229D02*
X551462Y170979D01*
Y107024D01*
X538300Y93862D01*
X474815D01*
X469653Y88700D01*
G01X469901Y94047D02*
Y96083D01*
X471680Y97862D01*
X536642D01*
X544962Y106182D01*
Y160317D01*
X549212Y164567D01*
G01X442800Y90934D02*
X445163Y93297D01*
Y102450D01*
G01D02*
X446663Y103950D01*
Y164754D01*
X442913Y168504D01*
G01X464173Y159055D02*
Y158073D01*
X459336Y153236D01*
Y144737D01*
X459246Y144647D01*
Y141181D01*
X459336Y141091D01*
Y130563D01*
X459246Y130473D01*
Y127008D01*
X459336Y126918D01*
Y120721D01*
X457766Y119151D01*
Y88336D01*
X456430Y87000D01*
G01X471766Y53745D02*
X472613D01*
X474801Y51557D01*
Y49368D01*
X472921Y47488D01*
Y45150D01*
G01X473100Y58000D02*
X472500Y58600D01*
Y62450D01*
G01X471766Y53745D02*
Y55568D01*
X473100Y56902D01*
Y58000D01*
G01X535048Y48397D02*
X532255D01*
X531252Y49400D01*
X528950D01*
G01X489730Y77724D02*
X484700D01*
X482256Y75280D01*
X478080D01*
X472500Y69700D01*
Y65950D01*
G01X489730Y77724D02*
X495348D01*
X509750Y63322D01*
Y48949D01*
X511599Y47100D01*
X526650D01*
X528950Y49400D01*
G01X535048Y54803D02*
X532189D01*
X530986Y53600D01*
X528950D01*
G01X477750Y34416D02*
X481316D01*
X483235Y36335D01*
G01X489836Y37907D02*
X486667D01*
X486568Y38006D01*
G01X483235Y36335D02*
X484906Y38006D01*
X486568D01*
G01X486550Y49100D02*
Y42136D01*
X486114Y41700D01*
G01X477750Y36384D02*
X479752D01*
X485068Y41700D01*
X486114D01*
G01X489750Y30000D02*
X486387Y26637D01*
X484414D01*
G01D02*
X482541Y28510D01*
X478050D01*
G01X476305Y53965D02*
Y53725D01*
X476315Y53715D01*
Y52872D01*
X476801Y52386D01*
Y49855D01*
X474890Y47944D01*
Y45450D01*
G01X476305Y53965D02*
Y60255D01*
X477300Y61250D01*
G01D02*
X480075D01*
X482475Y58850D01*
G01X491740Y63670D02*
X495365D01*
X499240Y59795D01*
G01X485975Y58850D02*
Y60296D01*
X484965Y61306D01*
Y63428D01*
G01D02*
X485207Y63670D01*
X491740D01*
G01X499240Y67545D02*
Y70336D01*
X496043Y73533D01*
X494171D01*
G01X485850Y67973D02*
Y70251D01*
X489132Y73533D01*
X494171D01*
G01X474890Y25350D02*
Y23270D01*
X476311Y21849D01*
X480851D01*
X481209Y21491D01*
X485104D01*
G01D02*
X485241D01*
X489750Y26000D01*
G01X481831Y17711D02*
X486410D01*
X489750Y21051D01*
Y22000D01*
G01X481831Y17711D02*
X475589D01*
X472921Y20379D01*
Y25650D01*
G01X496430Y22890D02*
X495610D01*
X493250Y25250D01*
Y26000D01*
G01X491270Y18877D02*
X491277Y18870D01*
X491870D01*
X493450Y20450D01*
Y21800D01*
X493250Y22000D01*
G01X489750Y34000D02*
X486229Y30479D01*
X477750D01*
G01X485674Y32924D02*
X486750Y34000D01*
X489750D01*
G01X549212Y178740D02*
X553462Y174490D01*
Y106195D01*
X539129Y91862D01*
X477329D01*
X475310Y89843D01*
G01X473172Y95508D02*
X473526Y95862D01*
X537471D01*
X546962Y105353D01*
Y156805D01*
X549212Y159055D01*
G01X479147Y102165D02*
X479869Y102887D01*
X504756D01*
X511101Y109232D01*
Y165826D01*
X513779Y168504D01*
G01X527953Y154331D02*
X530900Y151384D01*
Y110480D01*
X533080Y108300D01*
G01X549550Y61900D02*
X550328Y61122D01*
Y58081D01*
X551429Y56980D01*
X557230D01*
X557660Y57410D01*
Y60130D01*
G01X564500Y64100D02*
X562250D01*
X561541Y64809D01*
X556509D01*
X555100Y63400D01*
Y60130D01*
G01X552540Y53630D02*
X550269D01*
X548828Y55071D01*
Y58870D01*
X547700Y59998D01*
Y65550D01*
X549650Y67500D01*
G01X555625Y68750D02*
X550900D01*
X549650Y67500D01*
G01X573600Y54765D02*
Y49750D01*
G01Y62835D02*
Y67330D01*
X574759Y68489D01*
G01X542126Y174016D02*
X537496Y169386D01*
Y113566D01*
X538579Y112483D01*
X538732D01*
X540179Y111036D01*
G01X542126Y168504D02*
X539346Y165724D01*
Y114333D01*
G01X587300Y151400D02*
Y119871D01*
X611527Y95644D01*
Y81780D01*
X618110Y75197D01*
G01X594000Y151500D02*
Y115801D01*
X613550Y96251D01*
Y85150D01*
X621063Y77637D01*
Y69685D01*
G01X600000Y151500D02*
Y112899D01*
X615050Y97849D01*
Y89516D01*
X619920Y84646D01*
X621063D01*
G01X551500Y82400D02*
Y82100D01*
X551700Y81900D01*
X555327D01*
G01X559500Y76250D02*
Y81750D01*
X559250Y82000D01*
G01X555327Y81900D02*
X559150D01*
X559250Y82000D01*
G01X574759Y68489D02*
X578400Y72130D01*
Y74500D01*
G01X562160Y178600D02*
X563000Y177760D01*
Y157100D01*
X560231Y154331D01*
X556299D01*
G01X598964Y354128D02*
Y327536D01*
X607400Y319100D01*
Y299100D01*
G01X603597Y335950D02*
X602075Y337472D01*
Y339970D01*
G01X593748Y386961D02*
Y391550D01*
X592275Y393023D01*
X586155D01*
G01X600300Y574400D02*
X604000Y570700D01*
Y558436D01*
X586000Y540436D01*
Y413200D01*
X605400Y393800D01*
Y393400D01*
G01X610300Y574400D02*
X606500Y570600D01*
Y557400D01*
X588500Y539400D01*
Y414700D01*
X614022Y389178D01*
Y382345D01*
G01X618110Y90157D02*
Y98091D01*
X605400Y110801D01*
Y151400D01*
G01X616300D02*
Y136750D01*
X613500Y133950D01*
Y109728D01*
X618110Y105118D01*
G01X610900Y151500D02*
Y109216D01*
X620510Y99606D01*
X621063D01*
G01X618110Y120079D02*
Y128610D01*
X625390Y135890D01*
Y154390D01*
X622310Y157470D01*
G01X621600Y151600D02*
Y136800D01*
X615910Y131110D01*
Y119167D01*
X620510Y114567D01*
X621063D01*
G01X779527Y213779D02*
X777733Y211985D01*
Y210033D01*
X776944Y209244D01*
Y202074D01*
X772895Y198025D01*
Y189535D01*
X771940Y188580D01*
Y186750D01*
X755495Y170305D01*
X686094D01*
X644649Y211750D01*
X629901D01*
X607400Y234251D01*
Y299100D01*
G01X688650Y259500D02*
X685800Y262350D01*
X684410D01*
X677650Y269110D01*
Y299360D01*
X667199Y309811D01*
Y312089D01*
X668811Y313701D01*
X671280D01*
X674750Y317171D01*
Y317931D01*
X675555Y318736D01*
G01X672350Y317600D02*
X670451Y315701D01*
X667982D01*
X665199Y312918D01*
Y308982D01*
X675479Y298702D01*
Y242848D01*
X680452Y237875D01*
X690426D01*
X691300Y238749D01*
X695402D01*
X695902Y238249D01*
Y238248D01*
X697300Y236850D01*
X697350D01*
G01X639318Y354003D02*
X633203D01*
X631014Y351814D01*
Y347800D01*
G01X633574D02*
X639107D01*
X639878Y348571D01*
G01X643082Y353941D02*
X639878Y350737D01*
Y348571D01*
G01X629239Y387969D02*
X623487Y382217D01*
Y367595D01*
X623144Y367252D01*
Y342616D01*
X623239Y342521D01*
Y340929D01*
G01X618997Y349816D02*
Y346054D01*
X619877Y345174D01*
Y341380D01*
X618900Y340403D01*
Y338200D01*
G01X623239Y337429D02*
X619497D01*
X618997Y337929D01*
Y338200D01*
X618900D01*
G01X620139Y380400D02*
Y379505D01*
X620822Y378822D01*
Y375914D01*
G01X620139Y380400D02*
Y384061D01*
X620100Y384100D01*
G01X620822Y372414D02*
Y368632D01*
X620111Y367921D01*
G01D02*
X620644Y367388D01*
Y359948D01*
X619712Y359016D01*
X618997D01*
G01X608500Y343300D02*
Y339450D01*
G01X613087Y349816D02*
X610116D01*
X608500Y348200D01*
Y343300D01*
G01X613223Y372477D02*
X612466Y371720D01*
Y368519D01*
G01X613087Y359016D02*
Y361212D01*
X611559Y362740D01*
Y367612D01*
X612466Y368519D01*
G01X632220Y389694D02*
Y393520D01*
G01X637147Y396747D02*
Y394138D01*
X639791Y391494D01*
X642345D01*
G01X632220Y393520D02*
X635447Y396747D01*
X637147D01*
G01X607100Y351200D02*
X607964D01*
X609080Y352316D01*
X610926D01*
X612176Y353566D01*
X612766D01*
X613900Y354700D01*
X616000D01*
X617027Y355727D01*
Y359016D01*
G01X604258Y373437D02*
X603873Y373822D01*
Y379461D01*
G01D02*
Y380773D01*
X605462Y382362D01*
X607800D01*
G01X640960Y377294D02*
Y373215D01*
X635051Y367306D01*
X634661D01*
G01D02*
X634092D01*
X631014Y364228D01*
Y360600D01*
G01X638360Y383805D02*
X640960Y381205D01*
Y377294D01*
G01X642270Y383869D02*
X643200Y382939D01*
Y366300D01*
G01X639067Y362041D02*
X637692D01*
X636251Y360600D01*
X633574D01*
G01X639067Y362041D02*
X642012D01*
X643200Y363229D01*
Y366300D01*
G01X608500Y335950D02*
X603597D01*
G01X613223Y375977D02*
Y381546D01*
X614022Y382345D01*
G01X633772Y379591D02*
X637353D01*
G01X646220Y398994D02*
X654244D01*
X655800Y400550D01*
G01X646377Y406537D02*
X652670D01*
X655800Y403407D01*
Y400550D01*
G01X646377Y412537D02*
X642446D01*
X640891Y414092D01*
Y414908D01*
G01D02*
Y415790D01*
X642537Y417436D01*
X646469D01*
G01X696850Y75197D02*
X681697Y90350D01*
Y155597D01*
X681700Y155600D01*
G01X678100Y151500D02*
Y90835D01*
X699250Y69685D01*
X699803D01*
G01X689400Y155500D02*
Y149000D01*
X687227Y146827D01*
Y99780D01*
X696850Y90157D01*
G01X699803Y84646D02*
X694081D01*
X684594Y94133D01*
Y150394D01*
X685600Y151400D01*
G01X697400Y155500D02*
Y150300D01*
X692143Y145043D01*
Y109825D01*
X696850Y105118D01*
G01X693400Y151700D02*
Y149700D01*
X689773Y146073D01*
Y104403D01*
X694570Y99606D01*
X699803D01*
G01X705300Y155100D02*
Y149800D01*
X696850Y141350D01*
Y120079D01*
G01X701100Y151600D02*
Y150000D01*
X694650Y143550D01*
Y119167D01*
X699250Y114567D01*
X699803D01*
G01X734028Y182396D02*
X725804D01*
X724850Y183350D01*
Y189000D01*
X727150Y191300D01*
G01X729134Y213779D02*
X730800Y212113D01*
Y210051D01*
X731450Y209401D01*
Y207150D01*
X730000Y205700D01*
Y196800D01*
G01X727150Y191300D02*
X730000Y194150D01*
Y196800D01*
G01X725466Y200819D02*
X722000Y197353D01*
Y191450D01*
X722150Y191300D01*
G01X722322Y200935D02*
X720000Y198613D01*
Y190840D01*
X719250Y190090D01*
Y182037D01*
X720877Y180410D01*
X720878D01*
G01X725678Y180442D02*
X724932Y179696D01*
X721591D01*
X720878Y180409D01*
Y180410D01*
G01X716650Y191300D02*
Y192600D01*
X717700Y193650D01*
Y196400D01*
G01X718123Y201101D02*
Y199251D01*
X717700Y198828D01*
Y196400D01*
G01X716650Y181050D02*
X715650D01*
X713900Y182800D01*
Y188750D01*
X716450Y191300D01*
X716650D01*
G01X710079Y203664D02*
X705450Y199035D01*
Y191500D01*
X705650Y191300D01*
G01X718895Y207125D02*
X717000Y205230D01*
Y203797D01*
X710403Y197200D01*
G01X711150Y191300D02*
X711000Y191450D01*
Y194453D01*
X710403Y195050D01*
Y197200D01*
G01X699970Y197740D02*
X702230Y200000D01*
Y200020D01*
X703239Y201029D01*
X703381D01*
X703452Y200958D01*
G01X706357Y180801D02*
Y181699D01*
X708221Y183563D01*
Y197552D01*
X708253Y197584D01*
Y198091D01*
X713168Y203006D01*
Y207689D01*
G01X711150Y181050D02*
X710901Y180801D01*
X706357D01*
G01X725984Y213779D02*
X727674Y212089D01*
Y207359D01*
X728700Y206333D01*
Y200800D01*
X724700Y196800D01*
G01X735500D02*
Y195950D01*
X732000Y192450D01*
G01X713386Y261023D02*
X708365D01*
X705188Y264200D01*
X701471D01*
X700071Y265600D01*
X698584D01*
X696200Y267984D01*
X694150D01*
G01X685092Y244547D02*
Y244592D01*
X690000Y249500D01*
G01X716535Y251575D02*
X714921Y253189D01*
X710256D01*
X709068Y252001D01*
X702599D01*
X702100Y252500D01*
X697950D01*
X694850Y249400D01*
G01D02*
X694750Y249500D01*
X690000D01*
G01X718121Y256326D02*
X718137D01*
X719685Y257874D01*
G01X718089Y246834D02*
X718094D01*
X719685Y248425D01*
G01X718098Y259423D02*
Y259436D01*
X719685Y261023D01*
G01X716535Y264173D02*
X715185Y265523D01*
X709668D01*
X703581Y271610D01*
X701061D01*
X694293Y278378D01*
X693668D01*
G01X684897Y240430D02*
X687474D01*
X690094Y243050D01*
G01D02*
X694144Y247100D01*
X706125D01*
X710600Y251575D01*
X713386D01*
G01X718072Y265748D02*
X718093Y265727D01*
X718131D01*
X719685Y264173D01*
G01X718089Y249984D02*
X718094D01*
X719685Y251575D01*
G01X716535Y254724D02*
X715185Y256074D01*
X708875D01*
X707801Y255000D01*
X703200D01*
X701474Y256726D01*
X700636D01*
X699145Y258217D01*
G01X688550Y255400D02*
X691500D01*
X694317Y258217D01*
X699145D01*
G01X713386Y264173D02*
X708898D01*
X704180Y268891D01*
X703130D01*
G01X716535Y261023D02*
X715048Y262510D01*
X708463D01*
X704723Y266250D01*
X702250D01*
X700900Y267600D01*
X699413D01*
X694013Y273000D01*
X693300D01*
G01X718129Y253144D02*
X719685Y254700D01*
Y254724D01*
G01X700050Y244800D02*
X704000D01*
G01X716535Y248425D02*
X715185Y249775D01*
X710757D01*
X705782Y244800D01*
X704000D01*
G01X688650Y259500D02*
Y260050D01*
X690333Y261733D01*
X696167D01*
X696900Y261000D01*
X699404D01*
X702654Y257750D01*
Y257614D01*
X703854Y256414D01*
X706002D01*
X707462Y257874D01*
X713386D01*
G01Y248425D02*
X711348D01*
X702927Y240004D01*
X700504D01*
X697350Y236850D01*
G01X713386Y254724D02*
X713179Y254517D01*
X709417D01*
X708200Y253300D01*
X702999D01*
X702299Y254000D01*
X699000D01*
X698483Y254517D01*
X694500D01*
G01X685450Y249100D02*
Y250550D01*
X686800Y251900D01*
X691883D01*
X694500Y254517D01*
G01X693800Y264300D02*
X696900D01*
X698200Y263000D01*
X700329D01*
X703329Y260000D01*
X711553D01*
X712213Y259340D01*
X715069D01*
X716535Y257874D01*
G01X725466Y200819D02*
Y201972D01*
X723797Y203641D01*
Y209090D01*
X724372Y209665D01*
Y212242D01*
X722835Y213779D01*
G01X707923Y219765D02*
X709923D01*
X711724Y221566D01*
X715048D01*
X716535Y220079D01*
G01X708900Y214500D02*
X711674D01*
X712453Y215279D01*
X713898D01*
X715548Y216929D01*
X716535D01*
G01X699550Y207600D02*
Y211646D01*
X699453Y211743D01*
G01X699550Y207600D02*
X700600Y208650D01*
X705334D01*
X708900Y212216D01*
Y214500D01*
G01X719685Y223228D02*
X718111Y224802D01*
G01X706500Y212150D02*
Y215500D01*
X707929Y216929D01*
X713386D01*
G01Y223228D02*
X709615D01*
G01X719685Y229527D02*
X718111Y231101D01*
G01X696300Y215750D02*
X696373Y215823D01*
Y222092D01*
X703025Y228744D01*
X705641D01*
X706566Y227819D01*
X715094D01*
X716535Y226378D01*
G01X713386Y220079D02*
X712159D01*
X709909Y217829D01*
X707556D01*
X707156Y217429D01*
X705944D01*
X702900Y214385D01*
Y212350D01*
G01X707679Y233664D02*
X712399D01*
X713386Y232677D01*
G01X719685Y226378D02*
X718111Y227952D01*
G01X722322Y200935D02*
Y209058D01*
X721466Y209914D01*
Y215560D01*
X722835Y216929D01*
G01X704279Y226664D02*
X704565Y226378D01*
X713386D01*
G01X705529Y231064D02*
X706479Y232014D01*
X708363D01*
X708949Y232600D01*
X710735D01*
X712085Y231250D01*
X715896D01*
X716535Y230611D01*
Y229527D01*
G01Y235827D02*
X714865Y237497D01*
X706512D01*
X705779Y236764D01*
G01D02*
X704508Y235493D01*
Y233964D01*
G01X697350Y228400D02*
X698944D01*
X704508Y233964D01*
G01X706079Y240664D02*
X706361Y240946D01*
X711054D01*
X711474Y240526D01*
X714985D01*
X716535Y238976D01*
G01X706079Y240664D02*
X697815Y232400D01*
X697350D01*
G01X713386Y235827D02*
X710716D01*
G01X714945Y234230D02*
X716498Y232677D01*
X716535D01*
G01X726988Y204312D02*
X725984Y205316D01*
Y210630D01*
G01X719685D02*
Y209785D01*
X720629Y208841D01*
Y203607D01*
X718123Y201101D01*
G01X719685Y216929D02*
X718030Y215274D01*
X715896D01*
X715085Y214463D01*
Y213159D01*
X710078Y208152D01*
Y207444D01*
X711614Y205908D01*
Y205199D01*
X710079Y203664D01*
G01X719685Y213779D02*
X718221Y212315D01*
Y209197D01*
X718895Y208523D01*
Y207125D01*
G01X705364Y205864D02*
X705471D01*
X713386Y213779D01*
G01X705364Y205864D02*
Y202870D01*
X703452Y200958D01*
G01X716535Y213779D02*
Y212813D01*
X713168Y209446D01*
Y207689D01*
G01X719685Y220079D02*
X718111Y221653D01*
G01X719685Y232677D02*
X718110Y234252D01*
G01X709679Y239164D02*
X709867Y238976D01*
X713386D01*
G01X729134Y216929D02*
X727560Y215355D01*
G01X716116Y207469D02*
X716535Y207888D01*
Y210630D01*
G01X719685Y235827D02*
X718111Y237401D01*
G01X709079Y229564D02*
X713349D01*
X713386Y229527D01*
G01X703979Y219995D02*
X708901Y224917D01*
X714846D01*
X716535Y223228D01*
G01X719685Y238976D02*
X718111Y240550D01*
G01X713386Y242126D02*
X711812Y243700D01*
G01X716535Y242126D02*
X714961Y243700D01*
G01X732283Y216929D02*
X730709Y215355D01*
G01X725984Y216929D02*
X724410Y215355D01*
G01X732264Y204312D02*
X733162D01*
X737067Y208217D01*
Y212263D01*
X738583Y213779D01*
G01X699600Y203560D02*
X702980D01*
X703320Y203900D01*
G01X732283Y210630D02*
X733859Y212206D01*
G01X729800Y208400D02*
X729134Y209066D01*
Y210630D01*
G01X689050Y265100D02*
X691934Y267984D01*
X694150D01*
G01X706796Y295829D02*
X707440D01*
X712469Y290800D01*
X715105D01*
X716535Y289370D01*
G01X726895Y309117D02*
Y307906D01*
X727334Y307467D01*
Y300169D01*
X725984Y298819D01*
G01X711799Y304234D02*
X714987Y301046D01*
Y298316D01*
X716083Y297220D01*
X718134D01*
X719685Y295669D01*
G01X713386D02*
X712168D01*
X705268Y302569D01*
X704808D01*
X704763Y302614D01*
X697114D01*
X696200Y301700D01*
G01X713339Y306954D02*
X714562D01*
X717985Y303531D01*
Y300269D01*
X716535Y298819D01*
G01X726000Y322000D02*
X726580Y321420D01*
Y313616D01*
X730484Y309712D01*
Y300169D01*
X729134Y298819D01*
G01X724063Y306305D02*
X724296Y306072D01*
Y300280D01*
X722835Y298819D01*
G01X698039Y285854D02*
Y285411D01*
X698308Y285142D01*
Y281828D01*
X698250Y281770D01*
Y280155D01*
X707933Y270472D01*
X713386D01*
G01X707834Y293060D02*
X711524Y289370D01*
X713386D01*
G01X707079Y286964D02*
Y286054D01*
X710062Y283071D01*
X713386D01*
G01X704079Y300964D02*
X705487D01*
X712487Y293964D01*
X715090D01*
X716535Y292519D01*
G01X719200Y307400D02*
Y303946D01*
X719685Y303461D01*
Y301968D01*
G01Y298819D02*
X721135Y300269D01*
Y307799D01*
X719884Y309050D01*
X719848D01*
X713400Y315498D01*
Y316800D01*
G01X705579Y298464D02*
X706507D01*
X712452Y292519D01*
X713386D01*
G01X716535Y295669D02*
X715887D01*
X714437Y297119D01*
X712992D01*
X703211Y306900D01*
X699300D01*
G01X695508Y288964D02*
X696678Y287794D01*
X699280D01*
X701806Y285268D01*
X702532D01*
X708955Y278845D01*
X710976D01*
X711400Y278421D01*
X714885D01*
X716535Y276771D01*
G01X710679Y267894D02*
X711250Y267323D01*
X713386D01*
G01X721230Y284653D02*
X721243Y284666D01*
Y290961D01*
X719685Y292519D01*
G01X718099Y290964D02*
Y290956D01*
X719685Y289370D01*
G01X710329Y285214D02*
X710965Y284578D01*
X715028D01*
X716535Y283071D01*
G01X718117Y281465D02*
X719661Y279921D01*
X719685D01*
G01X718080Y284653D02*
X719662Y283071D01*
X719685D01*
G01X701708Y292364D02*
X704730Y289342D01*
Y286539D01*
X709969Y281300D01*
X715156D01*
X716535Y279921D01*
G01X713386Y286220D02*
X712110D01*
X701330Y297000D01*
X693300D01*
G01X706277Y279162D02*
Y276534D01*
X707711Y275100D01*
X715057D01*
X716535Y273622D01*
G01X718072Y278346D02*
X719647Y276771D01*
X719685D01*
G01X708409D02*
X713386D01*
G01Y298819D02*
X701105Y311100D01*
X696000D01*
G01X733892Y297246D02*
X733860D01*
X732283Y295669D01*
G01X729134D02*
X730708Y297243D01*
G01X713386Y279921D02*
X709740D01*
X699561Y290100D01*
X699000D01*
G01X688997Y277530D02*
X689845Y278378D01*
X693668D01*
G01X716535Y267323D02*
X714869Y268989D01*
X712959D01*
X712377Y269571D01*
X707227D01*
X703098Y273700D01*
X701800D01*
X696250Y279250D01*
Y282599D01*
X696308Y282657D01*
Y284313D01*
X695135Y285486D01*
X693578D01*
X693364Y285700D01*
X689050D01*
X688850Y285900D01*
G01X689809Y290474D02*
Y290259D01*
X688850Y289300D01*
Y285900D01*
G01X692750Y293200D02*
X692535D01*
X689809Y290474D01*
G01X688997Y273430D02*
X691201Y275634D01*
X694208D01*
X700242Y269600D01*
X702421D01*
X703130Y268891D01*
G01X718109Y272034D02*
X719671Y270472D01*
X719685D01*
G01X688997Y269230D02*
Y269697D01*
X692300Y273000D01*
X693300D01*
G01X688997Y281730D02*
X692552D01*
X694307Y283485D01*
G01X718000Y346250D02*
Y339266D01*
X730738Y326528D01*
Y317486D01*
X732371Y315853D01*
Y313336D01*
X732711Y312996D01*
Y308317D01*
X733633Y307395D01*
Y300169D01*
X732283Y298819D01*
G01X722468Y308964D02*
Y307044D01*
X722413Y306989D01*
Y304902D01*
X722835Y304480D01*
Y301968D01*
G01X725984Y295669D02*
X727558Y297243D01*
G01X722835Y295669D02*
X724409Y297243D01*
G01X720613Y321539D02*
X724543Y317609D01*
Y313803D01*
X728700Y309646D01*
Y302402D01*
X729134Y301968D01*
G01X700323Y283078D02*
Y281377D01*
X703472Y278228D01*
Y276309D01*
X707600Y272181D01*
X714826D01*
X716535Y270472D01*
G01X714090Y324790D02*
X714540D01*
X716690Y326940D01*
Y327000D01*
X716840Y327150D01*
Y330780D01*
X716690Y330930D01*
Y330950D01*
X716300Y331340D01*
G01X714090Y324790D02*
X710120Y324750D01*
X710060Y324810D01*
G01X711700Y345250D02*
X713500Y343450D01*
Y340230D01*
X728238Y325492D01*
Y314102D01*
X731485Y310855D01*
Y307225D01*
X732283Y306427D01*
Y301968D01*
G01X728038Y336182D02*
X729600Y334620D01*
Y333324D01*
X734738Y328186D01*
Y319144D01*
X737100Y316782D01*
Y300486D01*
X735433Y298819D01*
G01X722500Y341000D02*
Y338302D01*
X733238Y327564D01*
Y318522D01*
X735433Y316327D01*
Y301968D01*
G01X725984D02*
Y306858D01*
X724118Y308724D01*
Y309648D01*
X723152Y310614D01*
X722636D01*
X721830Y311420D01*
X719680D01*
X716010Y315090D01*
Y317240D01*
X713350Y319900D01*
X706300D01*
G01D02*
X706000Y320200D01*
Y324750D01*
G01X686250Y307000D02*
X686950Y306300D01*
X691200D01*
G01X718099Y287814D02*
Y287806D01*
X719685Y286220D01*
G01X695300Y306700D02*
X694900Y306300D01*
X691200D01*
G01X719685Y273622D02*
Y273638D01*
X718137Y275186D01*
G01X702939Y281484D02*
X704372Y280051D01*
Y276783D01*
X707533Y273622D01*
X713386D01*
G01X718109Y268934D02*
Y268899D01*
X719685Y267323D01*
G01X716535Y286220D02*
Y286228D01*
X714949Y287814D01*
G01X718300Y362900D02*
X718427Y362773D01*
Y358980D01*
G01X718000Y346250D02*
X717750Y346500D01*
X716652D01*
X714950Y348202D01*
Y354550D01*
X718427Y358027D01*
Y358980D01*
G01X732600Y346900D02*
X734179Y345321D01*
Y332989D01*
X737738Y329430D01*
Y320388D01*
X740100Y318026D01*
Y300336D01*
X738583Y298819D01*
G01X713500Y356150D02*
X711050D01*
X709139Y354239D01*
X709008D01*
G01D02*
Y354108D01*
X707679Y352779D01*
Y349305D01*
X710567Y346417D01*
Y346383D01*
X711700Y345250D01*
G01X727000Y346250D02*
Y337220D01*
X728038Y336182D01*
G01X727200Y356050D02*
X727840D01*
X729750Y354140D01*
Y347348D01*
X728652Y346250D01*
X727000D01*
G01X731400Y355950D02*
Y353075D01*
X733036Y351439D01*
G01D02*
X735679Y348796D01*
Y333611D01*
X739238Y330052D01*
Y321010D01*
X741732Y318516D01*
Y301968D01*
G01X732000Y341400D02*
Y333046D01*
X736238Y328808D01*
Y319766D01*
X738600Y317404D01*
Y312764D01*
X738583Y312747D01*
Y301968D01*
G01X722500Y341000D02*
Y346250D01*
G01X696700Y469850D02*
Y465573D01*
X696500Y465373D01*
G01D02*
X692427D01*
X690500Y467300D01*
Y469509D01*
G01X683000Y473384D02*
X681001Y475383D01*
X676418D01*
G01X668546Y464321D02*
X674416D01*
X675174Y465079D01*
G01D02*
Y470110D01*
X674600Y470684D01*
G01X676418Y475383D02*
X674600Y473565D01*
Y470684D01*
G01X680250Y489500D02*
Y498361D01*
X681639Y499750D01*
G01D02*
X689000D01*
G01D02*
Y497100D01*
X688600Y496700D01*
Y493591D01*
G01X672750Y493375D02*
Y496450D01*
X675300Y499000D01*
G01X675950Y503900D02*
Y499650D01*
X675300Y499000D01*
G01X715391Y479109D02*
X714282Y478000D01*
X708500D01*
X705384Y474884D01*
Y470930D01*
G01X702460Y484600D02*
X697992Y480132D01*
X697095D01*
G01X702390Y488810D02*
Y484670D01*
X702460Y484600D01*
G01X702390Y488810D02*
X705170D01*
X710330Y483650D01*
G01X697095Y480132D02*
X692422D01*
X690500Y478210D01*
Y477259D01*
G01X722122Y611840D02*
Y613529D01*
X720351Y615300D01*
X720300D01*
G01X716345Y611840D02*
Y613145D01*
X718500Y615300D01*
X720300D01*
G01X783860Y47062D02*
X780815D01*
G01X786420D02*
Y45285D01*
X784864Y43729D01*
X777666D01*
G01D02*
X776600Y42663D01*
Y35250D01*
G01X783125Y66750D02*
Y63610D01*
X786200Y60535D01*
G01X788980Y53562D02*
Y57755D01*
X786200Y60535D01*
G01X762765Y42200D02*
Y49031D01*
X762700Y49096D01*
Y50010D01*
G01Y58080D02*
Y64790D01*
X761600Y65890D01*
Y68300D01*
G01X777700Y77650D02*
X776085D01*
X773835Y75400D01*
X770001D01*
X769500Y75901D01*
Y78750D01*
G01X787000Y74250D02*
Y79550D01*
X786500Y80050D01*
X783350D01*
G01D02*
X780100D01*
X777700Y77650D01*
G01X776500Y82700D02*
X776142Y83058D01*
X773258D01*
X772060Y81860D01*
Y78750D01*
G01X763825Y89975D02*
X762740Y91060D01*
Y99750D01*
G01X765300D02*
Y93748D01*
X766260Y92788D01*
G01X769500Y91000D02*
X768048D01*
X766260Y92788D01*
G01X767860Y106250D02*
X770650D01*
X776200Y100700D01*
Y93050D01*
G01X782875Y86050D02*
X776701Y92224D01*
X776700D01*
X776200Y92724D01*
Y93050D01*
G01X789000Y100400D02*
X791700D01*
X792600Y101300D01*
G01X786750Y93550D02*
X784400Y95900D01*
Y99250D01*
G01X789000Y100400D02*
X786850D01*
X786450Y100000D01*
X785150D01*
X784400Y99250D01*
G01X766940Y72250D02*
X762950D01*
X761600Y70900D01*
Y68300D01*
G01X772800Y107550D02*
Y107700D01*
X775200Y110100D01*
X776300D01*
G01D02*
X781725D01*
G01X778760Y123150D02*
X778975Y123365D01*
X784161D01*
G01D02*
Y119039D01*
X785600Y117600D01*
G01X776850Y115050D02*
Y121240D01*
X778760Y123150D01*
G01X775600Y196700D02*
Y198757D01*
X777933Y201090D01*
Y208695D01*
X779527Y210289D01*
Y210630D01*
G01X775600Y196700D02*
Y191850D01*
X775500Y191750D01*
G01X787900Y196700D02*
X784400Y200200D01*
Y212056D01*
X782677Y213779D01*
G01X787900Y196700D02*
Y194550D01*
X790600Y191850D01*
G01X780500Y190500D02*
X779433Y191567D01*
Y208551D01*
X781180Y210298D01*
Y215432D01*
X782677Y216929D01*
G01X782500Y196800D02*
X783312Y197612D01*
Y209995D01*
X782677Y210630D01*
G01X782500Y196800D02*
Y194950D01*
X785600Y191850D01*
G01X793200Y196700D02*
X787310Y202590D01*
Y212465D01*
X785996Y213779D01*
X785827D01*
G01X793200Y196700D02*
Y194250D01*
X795600Y191850D01*
G01X770300Y196700D02*
Y202682D01*
X775552Y207934D01*
Y209804D01*
X776378Y210630D01*
G01X800600Y191850D02*
Y194800D01*
X798700Y196700D01*
G01D02*
X789477Y205923D01*
X789476D01*
X788976Y206423D01*
Y210630D01*
G01X758100Y191850D02*
Y195914D01*
X758947Y196761D01*
G01X757480Y210630D02*
Y202861D01*
X758947Y201394D01*
Y196761D01*
G01X754331Y210630D02*
X753679Y209978D01*
Y197546D01*
X752922Y196789D01*
G01X740900Y196750D02*
X742040Y197890D01*
Y198840D01*
X743492Y200292D01*
Y200593D01*
X743550Y200651D01*
Y202666D01*
X749579Y208695D01*
Y212177D01*
X751181Y213779D01*
G01X745300Y196300D02*
X745200Y196400D01*
Y198400D01*
X744700Y198900D01*
Y202388D01*
X751181Y208869D01*
Y210630D01*
G01X741300Y192250D02*
Y192300D01*
X745300Y196300D01*
G01X745700Y192450D02*
X747500Y194250D01*
Y200142D01*
X746891Y200751D01*
G01X749900Y192150D02*
X753900D01*
X754000Y192250D01*
G01D02*
X755729Y193979D01*
Y201712D01*
G01X762200Y192250D02*
Y201031D01*
X761780Y201451D01*
G01X741500Y201840D02*
X740040Y200380D01*
Y198931D01*
X738750Y197641D01*
Y194200D01*
X737000Y192450D01*
G01X735500Y196800D02*
Y199640D01*
X738583Y202723D01*
Y210630D01*
G01X810500Y196700D02*
X806400Y200800D01*
X797550D01*
X793495Y204855D01*
Y214505D01*
X792421Y215579D01*
X791566D01*
X790776Y216369D01*
Y217224D01*
X789702Y218298D01*
X787196D01*
X785827Y216929D01*
G01X788976Y242126D02*
X787402Y240552D01*
G01X788976Y216929D02*
Y216174D01*
X790606Y214544D01*
Y209239D01*
X792595Y207250D01*
Y204482D01*
X797177Y199900D01*
X799945D01*
X803145Y196700D01*
X804600D01*
G01X793700Y256262D02*
X792162Y254724D01*
X792126D01*
G01X752759Y218499D02*
X751189Y216929D01*
X751181D01*
G01X755909Y218514D02*
X754331Y216936D01*
Y216929D01*
G01X757480Y213779D02*
X755834Y215425D01*
X753371D01*
X752700Y214754D01*
Y208682D01*
X746891Y202873D01*
Y200751D01*
G01X754331Y213779D02*
X755729Y212381D01*
Y201712D01*
G01X757480Y216929D02*
X758857Y215552D01*
Y205425D01*
X761780Y202502D01*
Y201451D01*
G01X803160Y259454D02*
X796855D01*
X795275Y257874D01*
G01X788976Y254724D02*
X790550Y253150D01*
G01X790523Y256289D02*
Y256327D01*
X788976Y257874D01*
G01X800021Y243717D02*
X799983D01*
X798425Y245275D01*
G01X738583Y242126D02*
X737009Y240552D01*
G01X735433Y216929D02*
X733859Y215355D01*
G01X748031Y213779D02*
X746600Y212348D01*
Y207300D01*
X742700Y203400D01*
Y203040D01*
X741500Y201840D01*
G01X748031Y216929D02*
X746457Y215355D01*
G01X737029Y215337D02*
Y215375D01*
X738583Y216929D01*
G01X743279Y215364D02*
X744844Y216929D01*
X744882D01*
G01X741732D02*
X740158Y215355D01*
G01X743279Y212196D02*
X744862Y213779D01*
X744882D01*
G01X741294Y208274D02*
X740154Y209414D01*
Y212201D01*
X741732Y213779D01*
G01X743008Y206059D02*
X743277Y206328D01*
Y209085D01*
X741732Y210630D01*
G01X738583Y295669D02*
X740157Y297243D01*
G01X735433Y295669D02*
X737008Y297244D01*
G01X741732Y286220D02*
X740158Y284646D01*
G01X744881Y309000D02*
Y306806D01*
X743182Y305107D01*
Y300269D01*
X741732Y298819D01*
G01Y295669D02*
X743306Y297243D01*
G01X744882Y286220D02*
X743308Y284646D01*
G01X748031Y286220D02*
X746457Y284646D01*
G01X738583Y286220D02*
X737009Y284646D01*
G01X744882Y301968D02*
Y304080D01*
X746796Y305994D01*
Y310119D01*
X743232Y313683D01*
Y319138D01*
X740738Y321632D01*
Y330674D01*
X738286Y333126D01*
Y340430D01*
X738586Y340730D01*
G01X744400Y322800D02*
X744982Y322218D01*
Y314804D01*
X748264Y311522D01*
Y305085D01*
X747518Y304339D01*
Y303543D01*
X746481Y302506D01*
Y300418D01*
X744882Y298819D01*
G01Y295669D02*
X746456Y297243D01*
G01X735433Y286220D02*
X733859Y284646D01*
G01X738365Y355985D02*
X741229Y353121D01*
Y348949D01*
X738465Y346185D01*
G01D02*
Y340851D01*
X738586Y340730D01*
G01X767684Y518500D02*
Y524500D01*
G01X790459Y538770D02*
X788413Y540816D01*
X771109D01*
X767684Y537391D01*
Y524500D01*
G01X777100Y531200D02*
X777084Y531184D01*
Y526500D01*
G01X736600Y500000D02*
X738392Y498208D01*
Y493592D01*
X740869Y491115D01*
Y488766D01*
G01X790459Y532500D02*
Y538770D01*
G01X771559Y532000D02*
X776300D01*
X777100Y531200D01*
G01X813449Y66586D02*
Y63251D01*
X814900Y61800D01*
G01X822470Y65175D02*
X819095Y61800D01*
X814900D01*
G01X807006Y53252D02*
X809819D01*
X810413Y53846D01*
Y57000D01*
X809000Y58413D01*
Y62000D01*
G01D02*
Y64651D01*
X809349Y65000D01*
Y66586D01*
G01X836400Y61300D02*
X841270D01*
X841300Y61330D01*
G01X829970Y61300D02*
X820717D01*
X818017Y58600D01*
X813400D01*
X812000Y57200D01*
Y54100D01*
X812848Y53252D01*
X815076D01*
G01X829970Y61300D02*
X836400D01*
G01X813449Y70086D02*
Y73042D01*
X813349Y73142D01*
G01X809349Y70086D02*
Y73197D01*
G01X810500Y196700D02*
Y191950D01*
X810600Y191850D01*
G01X805600D02*
Y195700D01*
X804600Y196700D01*
G01X858820Y232979D02*
X832608D01*
X806511Y250150D01*
X804098D01*
X802673Y251575D01*
X801575D01*
G01X858820Y232979D02*
X880221D01*
X880952Y232248D01*
X882913D01*
G01X827988Y238779D02*
X833473Y235170D01*
X880370D01*
X881462Y236262D01*
X882871D01*
G01X827988Y238779D02*
X808542Y251575D01*
X804724D01*
G01X803150Y256336D02*
X803186D01*
X804724Y257874D01*
G01X799972Y256309D02*
X801537Y257874D01*
X801575D01*
G01X810277Y243190D02*
X809167Y244300D01*
X808217D01*
X807242Y245275D01*
X804724D01*
G01X810688Y238944D02*
X808261Y241371D01*
X805479D01*
X804724Y242126D01*
G01X803129Y240535D02*
Y240572D01*
X801575Y242126D01*
G01X803158Y237414D02*
X801596Y238976D01*
X801575D01*
G01X806862Y243302D02*
X806461Y243703D01*
X803147D01*
X801575Y245275D01*
G01X806918Y237804D02*
X805746Y238976D01*
X804724D01*
G01X851700Y382900D02*
X855586D01*
X857569Y384883D01*
G01X850300Y388800D02*
Y384300D01*
X851700Y382900D01*
G01X850300Y393800D02*
X856326D01*
X857664Y395138D01*
G01X865500Y403400D02*
Y402974D01*
X857664Y395138D01*
G01X830300Y393800D02*
X822958D01*
G01X818022Y393639D02*
X818183Y393800D01*
X822958D01*
G01X850300Y398800D02*
X856100D01*
X856463Y399163D01*
G01X861000Y403350D02*
X857000D01*
G01D02*
Y399700D01*
X856463Y399163D01*
G01X830300Y398800D02*
X825317D01*
X824717Y399400D01*
X822900D01*
G01D02*
X821353D01*
X820921Y398968D01*
X818317D01*
G01X830300Y403800D02*
X825821D01*
X823256Y406365D01*
G01X818688Y406705D02*
X822916D01*
X823256Y406365D01*
G01X814817Y398968D02*
X810362D01*
X810341Y398947D01*
G01X806400Y398700D02*
X810094D01*
X810341Y398947D01*
G01X818688Y403205D02*
X815703D01*
X813974Y404934D01*
G01D02*
X810100D01*
G01X888551Y237028D02*
X887785Y236262D01*
X882871D01*
G01X882913Y228748D02*
Y224837D01*
X883100Y224650D01*
G01D02*
X889750D01*
X892449Y227349D01*
Y230972D01*
G01X885562Y307755D02*
X891156Y313349D01*
X892850D01*
G01D02*
X894351D01*
X897344Y310356D01*
Y306791D01*
G01X881200Y316000D02*
Y316634D01*
X883157Y318591D01*
X885568D01*
G01X885562Y313755D02*
X882645D01*
X881200Y315200D01*
Y316000D01*
G01X883240Y301973D02*
X884988Y300225D01*
X887703D01*
G01D02*
X888637Y299291D01*
X893469D01*
G54D55*
X153549Y687715D03*
X434500Y52457D03*
Y42657D03*
Y47557D03*
X629860Y521543D03*
X703400Y558300D03*
X795224Y42000D03*
X821224D03*
G54D64*
X263491Y692574D03*
X260931D03*
X258371D03*
Y686074D03*
X263491D03*
X251091Y692774D03*
X248531D03*
X245971D03*
Y686274D03*
X251091D03*
X271240Y686350D03*
X273800D03*
X271240Y692850D03*
X276360Y686350D03*
Y692850D03*
X369095Y217923D03*
X366535D03*
X363975D03*
Y211423D03*
X369095D03*
X366340Y487050D03*
X368900D03*
X371460D03*
Y493550D03*
X366340D03*
X557660Y60130D03*
X555100D03*
X552540D03*
Y53630D03*
X557660D03*
X707944Y470930D03*
X705384D03*
X702824D03*
Y464430D03*
X707944D03*
X783860Y47062D03*
X786420D03*
X788980D03*
Y53562D03*
X783860D03*
X762740Y99750D03*
X765300D03*
X767860D03*
Y106250D03*
X762740D03*
X772060Y78750D03*
X769500D03*
X766940D03*
Y72250D03*
X772060D03*
G54D73*
X320750Y592060D03*
Y589500D03*
Y586940D03*
X327250D03*
Y592060D03*
G54D139*
X815076Y55812D03*
Y53252D03*
Y50692D03*
X807006D03*
Y53252D03*
Y55812D03*
G54D19*
X34070Y48070D03*
Y54070D03*
X93640Y54860D03*
Y60860D03*
G54D91*
X369969Y586358D03*
X507322Y27993D03*
X502622D03*
X582090Y54480D03*
X646377Y412337D03*
X642660Y567843D03*
X708000Y457300D03*
X675174Y464879D03*
X731076Y601429D03*
X782500Y420800D03*
X762400Y478700D03*
X885562Y313555D03*
X880223Y390417D03*
G54D46*
X134700Y694850D03*
G54D37*
X49900Y671384D03*
X117700Y515200D03*
X85500Y632700D03*
X81784Y667900D03*
X203650Y633050D03*
X207060Y629620D03*
X170100Y704600D03*
X210520Y629310D03*
X247400Y639400D03*
X225400Y713000D03*
X263000Y675700D03*
X328659Y536059D03*
X317600Y606800D03*
X322100Y641700D03*
X314920Y678920D03*
X311704Y712120D03*
X366699Y201221D03*
X521800Y49800D03*
X559200Y40500D03*
X633800Y337900D03*
X614000Y337300D03*
X645300Y526200D03*
X702460Y481050D03*
X728559Y474298D03*
X676194Y586129D03*
X723676Y587629D03*
X776200Y51200D03*
X786600Y416200D03*
X794500Y497600D03*
X757099Y522966D03*
X826284Y501900D03*
X883100Y221100D03*
G54D28*
G01X209842Y583464D02*
X208268Y581890D01*
X208267D01*
G01X195669Y540945D02*
X197243Y539371D01*
G01X167323Y569291D02*
X168898Y570866D01*
G01X157874Y572441D02*
X156299Y570866D01*
G01X157874Y578740D02*
X156299Y580315D01*
G01X167323Y562992D02*
X168898Y561417D01*
G01X167323Y556693D02*
X165748Y558268D01*
G01X183071Y578740D02*
X184646Y577165D01*
G01X186220Y578740D02*
X187795Y577165D01*
G01X183071Y572441D02*
X184646Y574016D01*
G01X189370Y572441D02*
X190945Y570866D01*
G01X192519Y572441D02*
X190944Y574016D01*
G01X183071Y569291D02*
X184646Y570866D01*
G01X187795Y592914D02*
X187794D01*
X186220Y594488D01*
G01X183071Y562992D02*
X183797Y562266D01*
X185494D01*
X186220Y562992D01*
G01D02*
X187795Y564567D01*
G01X195669Y578740D02*
X194743Y579666D01*
X193445D01*
X192519Y578740D01*
G01X203542Y589764D02*
Y589763D01*
X201968Y588189D01*
G01X186220Y585039D02*
Y585040D01*
X187794Y586614D01*
G01X200393Y589764D02*
Y589763D01*
X198819Y588189D01*
G01X195669Y591338D02*
X197243Y592912D01*
Y592913D01*
G01X168898Y589764D02*
Y589763D01*
X170472Y588189D01*
G01X172048Y589764D02*
Y589763D01*
X173622Y588189D01*
G01X156297Y558267D02*
X157872Y559842D01*
X157874D01*
G01X172048Y555120D02*
X172049D01*
X173622Y556693D01*
G01X153149Y536221D02*
X153150D01*
X154724Y537795D01*
G01X206692Y555120D02*
X206691D01*
X205118Y556693D01*
G01X203542Y545671D02*
X203541D01*
X201968Y547244D01*
G01X183071Y566142D02*
X183072D01*
X184646Y567716D01*
G01X187795D02*
X186221Y566142D01*
X186220D01*
G01X183071Y575590D02*
X183072D01*
X184646Y574016D01*
G01D02*
X186220Y572442D01*
Y572441D01*
G01Y575590D02*
X186221D01*
X187795Y574016D01*
G01X190945Y577165D02*
X192519Y578739D01*
Y578740D01*
G01X187794Y586614D02*
X186220Y588188D01*
Y588189D01*
G01X197243Y592913D02*
X198818Y591338D01*
X198819D01*
G01X168898Y570866D02*
X170472Y572440D01*
Y572441D01*
G01X184646Y555120D02*
X184647D01*
X186220Y556693D01*
G01X184646Y567716D02*
X186220Y569290D01*
Y569291D01*
G01X187795Y574016D02*
X189369Y575590D01*
X189370D01*
G01X187795Y577165D02*
X189370Y578740D01*
G01Y569291D02*
X187795Y570866D01*
G01X189370Y566142D02*
X189371D01*
X190945Y567716D01*
G01X195669Y566142D02*
X195668D01*
X194094Y567716D01*
G01X192519Y566142D02*
X192520D01*
X194094Y567716D01*
G01X192519Y562992D02*
Y566142D01*
G01X189370Y562992D02*
X192519D01*
G01X195669D02*
Y566142D01*
G01X192519D02*
X190945Y567716D01*
G01X195669Y572441D02*
X192519D01*
G01X195669Y569291D02*
X194094Y567716D01*
G01X192519Y569291D02*
Y569292D01*
X190945Y570866D01*
G01X192519Y575590D02*
Y575591D01*
X190945Y577165D01*
G01X192519Y575590D02*
X195669D01*
G01X165748Y583464D02*
X167322Y581890D01*
X167323D01*
G01X173622Y588189D02*
X175197Y589764D01*
G01X173622Y585039D02*
Y588189D01*
G01X167323Y575590D02*
X170472Y572441D01*
G01X184645Y589764D02*
X186219Y591338D01*
X186220D01*
G01X173622Y572441D02*
X172047Y570866D01*
G01X198819Y553543D02*
Y553544D01*
X200395Y555120D01*
G01D02*
X201968Y556693D01*
G01X181497Y551970D02*
X181498D01*
X183071Y553543D01*
G01X181497Y589764D02*
Y589763D01*
X183071Y588189D01*
G01X206692Y567718D02*
X206691D01*
X205118Y569291D01*
G01X206692Y558269D02*
X206691D01*
X205118Y559842D01*
G01X206692Y561419D02*
X206691D01*
X205118Y562992D01*
G01X206692Y564569D02*
X206691D01*
X205118Y566142D01*
G01X194093Y586614D02*
Y586613D01*
X192519Y585039D01*
G01X178347Y551970D02*
X178348D01*
X179921Y553543D01*
G01X175197Y551970D02*
X175198D01*
X176771Y553543D01*
G01X175197Y558268D02*
X173623Y559842D01*
X173622D01*
G01X178347Y589764D02*
Y589763D01*
X179921Y588189D01*
G01X176771D02*
X176772D01*
X178347Y589764D01*
G01X173622Y566142D02*
X173621D01*
X172048Y564569D01*
G01X173622Y562992D02*
Y562995D01*
X172048Y564569D01*
G01X173622Y569291D02*
X173621D01*
X172047Y567717D01*
G01X175298Y577266D02*
X176095Y578063D01*
Y580466D01*
X174671Y581890D01*
X173622D01*
G01X186220Y594488D02*
X186595Y594863D01*
Y597263D01*
X186220Y597638D01*
G01X205118Y603937D02*
X203605Y605450D01*
G01X153149Y605513D02*
X154724Y603938D01*
Y603937D01*
G01X198819Y594488D02*
X200393Y596062D01*
Y596063D01*
G01D02*
X198819Y597637D01*
Y597638D01*
G01X203605Y605450D02*
X203463D01*
X201968Y603955D01*
Y603937D01*
G01X206700Y695400D02*
Y697000D01*
X205345Y698355D01*
X204236D01*
G01X205827Y688956D02*
Y690273D01*
X206700Y691146D01*
Y695400D01*
G01X214567Y588189D02*
X212992Y586614D01*
G01X216141D02*
Y586613D01*
X214567Y585039D01*
G01X321208Y519411D02*
X320629Y519990D01*
X320331D01*
X317870Y522451D01*
G01Y525011D02*
X321175D01*
X323661Y522525D01*
X325136D01*
G01X281645Y549394D02*
X285800D01*
G01X282600Y685650D02*
X281850Y686400D01*
X279400D01*
G01X366340Y493550D02*
X362920D01*
X361920Y492550D01*
X361600D01*
X360800Y491750D01*
G01D02*
X357750D01*
X357450Y491450D01*
G01X352410Y672460D02*
X358296D01*
G01X374610Y695500D02*
X379358D01*
X380329Y696471D01*
G01X552540Y60130D02*
Y64530D01*
G01X722835Y235827D02*
X724410Y234252D01*
G01X722835Y242126D02*
X724410Y240551D01*
G01Y265748D02*
X725984Y264174D01*
Y264173D01*
G01X722835Y261023D02*
X722836D01*
X724410Y259449D01*
G01D02*
X725984Y257875D01*
Y257874D01*
G01X722835Y267323D02*
X724410Y265748D01*
G01X722835Y273622D02*
X724410Y272047D01*
G01D02*
X725984Y270473D01*
Y270472D01*
G01X724410Y278346D02*
X725984Y276772D01*
Y276771D01*
G01X722835Y279921D02*
X724410Y278346D01*
G01X702824Y470930D02*
Y476476D01*
G01X731594Y482890D02*
X733142Y481342D01*
X735414D01*
G01X783860Y53562D02*
X782672Y54750D01*
X779400D01*
G01X777700Y74150D02*
X776050D01*
X774150Y72250D01*
X772060D01*
G01X762740Y106250D02*
Y112260D01*
X762000Y113000D01*
G01X761600Y207300D02*
X763077Y208777D01*
Y209928D01*
X763779Y210630D01*
G01X774803Y265749D02*
X773228Y264174D01*
Y264173D01*
G01X754331Y245275D02*
X755907Y246851D01*
G01X741732Y245275D02*
X743307Y246850D01*
G01X744882Y242126D02*
X744845D01*
X743281Y240562D01*
G01X744882Y261023D02*
X744844D01*
X743282Y259461D01*
G01X751181Y261023D02*
X751144D01*
X749582Y259461D01*
G01X763779Y261023D02*
Y260986D01*
X762218Y259425D01*
G01X757480Y261023D02*
X757444D01*
X755882Y259461D01*
G01X744882Y254724D02*
X744845D01*
X743282Y253161D01*
G01X751181Y254724D02*
Y254723D01*
X749608Y253150D01*
G01X763779Y254724D02*
X763743D01*
X762168Y253149D01*
G01X751181Y248425D02*
X751144D01*
X749569Y246850D01*
G01X763779Y248425D02*
X763742D01*
X762167Y246850D01*
G01X757480Y254724D02*
X757444D01*
X755869Y253149D01*
G01X749580Y240563D02*
X751143Y242126D01*
X751181D01*
G01X755880Y240563D02*
X757443Y242126D01*
X757480D01*
G01X743281Y240562D02*
X741732Y239013D01*
Y238976D01*
G01X743282Y265761D02*
X741732Y264211D01*
Y264173D01*
G01X749582Y265761D02*
X748031Y264210D01*
Y264173D01*
G01X762181Y265762D02*
X760630Y264211D01*
Y264173D01*
G01X743282Y259461D02*
X741732Y257911D01*
Y257874D01*
G01X749582Y259461D02*
X748031Y257910D01*
Y257874D01*
G01X762218Y259425D02*
X760667Y257874D01*
X760630D01*
G01X755882Y259461D02*
X754331Y257910D01*
Y257874D01*
G01X755868Y265748D02*
X754331Y264211D01*
Y264173D01*
G01X743282Y253161D02*
X741732Y251611D01*
Y251575D01*
G01X749608Y253150D02*
X748033Y251575D01*
X748031D01*
G01X762168Y253149D02*
X760630Y251611D01*
Y251575D01*
G01X749569Y246850D02*
X748031Y245312D01*
Y245275D01*
G01X755907Y246851D02*
X757480Y248424D01*
Y248425D01*
G01X762167Y246850D02*
X760630Y245313D01*
Y245275D01*
G01X755869Y253149D02*
X754331Y251611D01*
Y251575D01*
G01X743307Y246850D02*
X744882Y248425D01*
G01X773228Y245275D02*
Y245312D01*
X771653Y246887D01*
G01X766929Y245275D02*
Y245312D01*
X768467Y246850D01*
G01Y253149D02*
X766929Y251611D01*
Y251575D01*
G01X768518Y259425D02*
X766967Y257874D01*
X766929D01*
G01X770079Y254724D02*
X770039D01*
X768467Y253152D01*
Y253149D01*
G01X770079Y261023D02*
Y260986D01*
X768518Y259425D01*
G01X768480Y265762D02*
X766929Y264211D01*
Y264173D01*
G01X788976Y220079D02*
X790551Y221654D01*
G01D02*
X792125Y223228D01*
X792126D01*
G01X741732D02*
X740158Y221654D01*
G01X738583Y220079D02*
X740158Y221654D01*
G01X795275Y220079D02*
X796850Y221654D01*
G01X781120Y284665D02*
X779527Y283072D01*
Y283071D01*
G01X784249Y281464D02*
X785827Y283042D01*
Y283071D01*
G01X796862Y281522D02*
Y281498D01*
X795285Y279921D01*
X795275D01*
G01X796832Y272064D02*
X795275Y270507D01*
Y270472D01*
G01X787438Y275197D02*
X785864Y276771D01*
X785827D01*
G01X790551Y278384D02*
X789014Y279921D01*
X788976D01*
G01X787426Y272060D02*
X788976Y270510D01*
Y270472D01*
G01X743282Y265761D02*
X744844Y267323D01*
X744882D01*
G01X751181D02*
X751144D01*
X749582Y265761D01*
G01X763779Y267323D02*
X763742D01*
X762181Y265762D01*
G01X757480Y267323D02*
X757443D01*
X755868Y265748D01*
G01X749581Y272060D02*
Y272022D01*
X748031Y270472D01*
G01X752230Y483311D02*
X749738D01*
X749425Y482998D01*
Y482971D01*
X748078Y481624D01*
X748051D01*
X747769Y481342D01*
X735414D01*
G01X744806Y488766D02*
Y495350D01*
G01D02*
Y497356D01*
X745700Y498250D01*
G01X799999Y290944D02*
X801573Y289370D01*
X801575D01*
G01X809968Y290464D02*
X808783Y289279D01*
X804815D01*
X804724Y289370D01*
X72577Y578589D03*
X69427D03*
X66278D03*
X72577Y581738D03*
X69427D03*
X66278D03*
X72577Y584888D03*
X69427D03*
X66278D03*
X72577Y540794D03*
X69427D03*
X66278D03*
X72577Y543943D03*
X69427D03*
X66278D03*
X72577Y537644D03*
X69427D03*
X66278D03*
X72577Y547093D03*
X69427D03*
X66278D03*
X72577Y550242D03*
X69427D03*
X66278D03*
X72577Y553392D03*
X69427D03*
X66278D03*
X72577Y556542D03*
X69427D03*
X66278D03*
X72577Y559691D03*
X69427D03*
X66278D03*
X72577Y562841D03*
X69427D03*
X66278D03*
X72577Y565990D03*
X69427D03*
X66278D03*
X72577Y569140D03*
X69427D03*
X66278D03*
X72577Y572290D03*
X69427D03*
X66278D03*
X72577Y575439D03*
X69427D03*
X66278D03*
X91474Y569140D03*
Y572290D03*
Y575439D03*
Y578589D03*
Y581738D03*
Y584888D03*
X88325Y578589D03*
X85175D03*
X88325Y581738D03*
X85175D03*
X88325Y584888D03*
X85175D03*
Y547093D03*
X91474Y540794D03*
X88325D03*
X85175D03*
X91474Y543943D03*
X88325D03*
X85175D03*
X91474Y537644D03*
X88325D03*
X85175D03*
X91474Y547093D03*
X88325D03*
X91474Y550242D03*
X88325D03*
X85175D03*
X91474Y553392D03*
X88325D03*
X85175D03*
X91474Y556542D03*
X88325D03*
X85175D03*
X91474Y559691D03*
X88325D03*
X85175D03*
X91474Y562841D03*
X88325D03*
X85175D03*
X91474Y565990D03*
X88325D03*
X85175D03*
X88325Y569140D03*
X85175D03*
X88325Y572290D03*
X85175D03*
X88325Y575439D03*
X85175D03*
X154724Y547244D03*
Y550394D03*
Y553543D03*
Y556693D03*
Y559842D03*
Y562992D03*
Y566142D03*
Y569291D03*
Y572441D03*
Y575590D03*
Y578740D03*
Y581890D03*
Y585039D03*
Y588189D03*
Y591338D03*
X157874Y547244D03*
Y550394D03*
Y553543D03*
Y556693D03*
Y559842D03*
Y562992D03*
Y566142D03*
Y569291D03*
Y572441D03*
Y575590D03*
Y578740D03*
Y581890D03*
Y585039D03*
Y588189D03*
Y591338D03*
X161023Y547244D03*
Y550394D03*
Y553543D03*
Y556693D03*
Y559842D03*
Y562992D03*
Y566142D03*
Y569291D03*
Y572441D03*
Y575590D03*
Y578740D03*
Y581890D03*
Y585039D03*
Y588189D03*
Y591338D03*
X164173Y537795D03*
Y540945D03*
Y544094D03*
Y547244D03*
Y550394D03*
Y553543D03*
Y556693D03*
Y559842D03*
Y562992D03*
Y566142D03*
Y569291D03*
Y572441D03*
Y575590D03*
Y578740D03*
Y581890D03*
Y585039D03*
Y588189D03*
Y591338D03*
X167323Y537795D03*
Y540945D03*
Y544094D03*
Y547244D03*
Y550394D03*
Y553543D03*
Y556693D03*
Y559842D03*
Y562992D03*
Y566142D03*
Y569291D03*
Y572441D03*
Y575590D03*
Y578740D03*
Y581890D03*
Y585039D03*
Y588189D03*
Y591338D03*
X170472Y537795D03*
Y540945D03*
Y544094D03*
Y547244D03*
Y550394D03*
Y553543D03*
Y556693D03*
Y559842D03*
Y562992D03*
Y566142D03*
Y569291D03*
Y572441D03*
Y575590D03*
Y578740D03*
Y581890D03*
Y585039D03*
Y588189D03*
Y591338D03*
X173622Y537795D03*
Y540945D03*
Y544094D03*
Y547244D03*
Y550394D03*
Y553543D03*
Y556693D03*
Y559842D03*
Y562992D03*
Y566142D03*
Y569291D03*
Y572441D03*
Y575590D03*
Y578740D03*
Y581890D03*
Y585039D03*
Y588189D03*
Y591338D03*
X176771Y537795D03*
Y540945D03*
Y544094D03*
Y547244D03*
Y550394D03*
Y553543D03*
Y556693D03*
Y585039D03*
Y588189D03*
Y591338D03*
X179921Y537795D03*
Y540945D03*
Y544094D03*
Y547244D03*
Y550394D03*
Y553543D03*
Y556693D03*
Y562992D03*
Y566142D03*
Y569291D03*
Y572441D03*
Y575590D03*
Y578740D03*
Y585039D03*
Y588189D03*
Y591338D03*
X183071Y537795D03*
Y540945D03*
Y544094D03*
Y547244D03*
Y550394D03*
Y553543D03*
Y556693D03*
Y562992D03*
Y566142D03*
Y569291D03*
Y572441D03*
Y575590D03*
Y578740D03*
Y585039D03*
Y588189D03*
Y591338D03*
X186220Y537795D03*
Y540945D03*
Y544094D03*
Y547244D03*
Y550394D03*
Y553543D03*
Y556693D03*
Y562992D03*
Y566142D03*
Y569291D03*
Y572441D03*
Y575590D03*
Y578740D03*
Y585039D03*
Y588189D03*
Y591338D03*
X189370Y537795D03*
Y540945D03*
Y544094D03*
Y547244D03*
Y550394D03*
Y553543D03*
Y556693D03*
Y562992D03*
Y566142D03*
Y569291D03*
Y572441D03*
Y575590D03*
Y578740D03*
Y585039D03*
Y588189D03*
Y591338D03*
X192519Y537795D03*
Y540945D03*
Y544094D03*
Y547244D03*
Y550394D03*
Y553543D03*
Y556693D03*
Y562992D03*
Y566142D03*
Y569291D03*
Y572441D03*
Y575590D03*
Y578740D03*
Y585039D03*
Y588189D03*
Y591338D03*
X195669Y537795D03*
Y540945D03*
Y544094D03*
Y547244D03*
Y550394D03*
Y553543D03*
Y556693D03*
Y562992D03*
Y566142D03*
Y569291D03*
Y572441D03*
Y575590D03*
Y578740D03*
Y585039D03*
Y588189D03*
Y591338D03*
X198819Y537795D03*
Y540945D03*
Y544094D03*
Y547244D03*
Y550394D03*
Y553543D03*
Y556693D03*
Y585039D03*
Y588189D03*
Y591338D03*
X201968Y537795D03*
Y540945D03*
Y544094D03*
Y547244D03*
Y550394D03*
Y553543D03*
Y556693D03*
Y559842D03*
Y562992D03*
Y566142D03*
Y569291D03*
Y572441D03*
Y575590D03*
Y578740D03*
Y581890D03*
Y585039D03*
Y588189D03*
Y591338D03*
X205118Y537795D03*
Y540945D03*
Y544094D03*
Y547244D03*
Y550394D03*
Y553543D03*
Y556693D03*
Y559842D03*
Y562992D03*
Y566142D03*
Y569291D03*
Y572441D03*
Y575590D03*
Y578740D03*
Y581890D03*
Y585039D03*
Y588189D03*
Y591338D03*
X208267Y537795D03*
Y540945D03*
Y544094D03*
Y547244D03*
Y550394D03*
Y553543D03*
Y556693D03*
Y559842D03*
Y562992D03*
Y566142D03*
Y569291D03*
Y572441D03*
Y575590D03*
Y578740D03*
Y581890D03*
Y585039D03*
Y588189D03*
Y591338D03*
X154724Y594488D03*
X157874D03*
X161023D03*
X164173D03*
Y597638D03*
Y600787D03*
Y603937D03*
X167323Y594488D03*
Y597638D03*
Y600787D03*
Y603937D03*
X170472Y594488D03*
Y597638D03*
Y600787D03*
Y603937D03*
X173622Y594488D03*
Y597638D03*
Y600787D03*
Y603937D03*
X176771Y594488D03*
Y597638D03*
Y600787D03*
Y603937D03*
X179921Y594488D03*
Y597638D03*
Y600787D03*
Y603937D03*
X183071Y594488D03*
Y597638D03*
Y600787D03*
Y603937D03*
X186220Y594488D03*
Y597638D03*
Y600787D03*
Y603937D03*
X189370Y594488D03*
Y597638D03*
Y600787D03*
Y603937D03*
X192519Y594488D03*
Y597638D03*
Y600787D03*
Y603937D03*
X195669Y594488D03*
Y597638D03*
Y600787D03*
Y603937D03*
X198819Y594488D03*
Y597638D03*
Y600787D03*
Y603937D03*
X201968Y594488D03*
Y597638D03*
Y600787D03*
Y603937D03*
X205118Y594488D03*
Y597638D03*
Y600787D03*
Y603937D03*
X208267Y594488D03*
Y597638D03*
Y600787D03*
Y603937D03*
X211417Y537795D03*
Y540945D03*
Y544094D03*
Y547244D03*
Y550394D03*
Y553543D03*
Y556693D03*
Y559842D03*
Y562992D03*
Y566142D03*
Y569291D03*
Y572441D03*
Y575590D03*
Y578740D03*
Y581890D03*
Y585039D03*
Y588189D03*
Y591338D03*
X214567Y547244D03*
Y550394D03*
Y553543D03*
Y556693D03*
Y559842D03*
Y562992D03*
Y566142D03*
Y569291D03*
Y572441D03*
Y575590D03*
Y578740D03*
Y581890D03*
Y585039D03*
Y588189D03*
Y591338D03*
X217716Y547244D03*
Y550394D03*
Y553543D03*
Y556693D03*
Y559842D03*
Y562992D03*
Y566142D03*
Y569291D03*
Y572441D03*
Y575590D03*
Y578740D03*
Y581890D03*
Y585039D03*
Y588189D03*
Y591338D03*
X220866Y547244D03*
Y550394D03*
Y553543D03*
Y556693D03*
Y559842D03*
Y562992D03*
Y566142D03*
Y569291D03*
Y572441D03*
Y575590D03*
Y578740D03*
Y581890D03*
Y585039D03*
Y588189D03*
Y591338D03*
X211417Y594488D03*
Y597638D03*
Y600787D03*
Y603937D03*
X214567Y594488D03*
X217716D03*
X220866D03*
X713386Y264173D03*
X716535D03*
X719685D03*
X722835D03*
X725984D03*
X729134D03*
X732283D03*
X713386Y261023D03*
X716535D03*
X719685D03*
X722835D03*
X725984D03*
X729134D03*
X732283D03*
X713386Y257874D03*
X716535D03*
X719685D03*
X722835D03*
X725984D03*
X729134D03*
X732283D03*
X713386Y254724D03*
X716535D03*
X719685D03*
X722835D03*
X725984D03*
X729134D03*
X732283D03*
X713386Y251575D03*
X716535D03*
X719685D03*
X722835D03*
X725984D03*
X729134D03*
X732283D03*
X713386Y248425D03*
X716535D03*
X719685D03*
X722835D03*
X725984D03*
X729134D03*
X732283D03*
X713386Y245275D03*
X716535D03*
X719685D03*
X722835D03*
X725984D03*
X729134D03*
X732283D03*
X713386Y242126D03*
X716535D03*
X719685D03*
X722835D03*
X725984D03*
X729134D03*
X732283D03*
X713386Y238976D03*
X716535D03*
X719685D03*
X722835D03*
X725984D03*
X729134D03*
X732283D03*
X713386Y235827D03*
X716535D03*
X719685D03*
X722835D03*
X725984D03*
X729134D03*
X732283D03*
X713386Y232677D03*
X716535D03*
X719685D03*
X722835D03*
X725984D03*
X729134D03*
X732283D03*
X713386Y229527D03*
X716535D03*
X719685D03*
X722835D03*
X725984D03*
X729134D03*
X732283D03*
X713386Y226378D03*
X716535D03*
X719685D03*
X722835D03*
X725984D03*
X729134D03*
X732283D03*
X713386Y223228D03*
X716535D03*
X719685D03*
X722835D03*
X725984D03*
X729134D03*
X732283D03*
X713386Y220079D03*
X716535D03*
X719685D03*
X722835D03*
X725984D03*
X729134D03*
X732283D03*
X722835Y216929D03*
X725984D03*
X729134D03*
X732283D03*
X722835Y213779D03*
X725984D03*
X729134D03*
X732283D03*
X722835Y210630D03*
X725984D03*
X729134D03*
X732283D03*
X722835Y301968D03*
X725984D03*
X729134D03*
X732283D03*
X722835Y298819D03*
X725984D03*
X729134D03*
X732283D03*
X722835Y295669D03*
X725984D03*
X729134D03*
X732283D03*
X713386Y292519D03*
X716535D03*
X719685D03*
X722835D03*
X725984D03*
X729134D03*
X732283D03*
X713386Y289370D03*
X716535D03*
X719685D03*
X722835D03*
X725984D03*
X729134D03*
X732283D03*
X713386Y286220D03*
X716535D03*
X719685D03*
X722835D03*
X725984D03*
X729134D03*
X732283D03*
X713386Y283071D03*
X716535D03*
X719685D03*
X722835D03*
X725984D03*
X729134D03*
X732283D03*
X713386Y279921D03*
X716535D03*
X719685D03*
X722835D03*
X725984D03*
X729134D03*
X732283D03*
X713386Y276771D03*
X716535D03*
X719685D03*
X722835D03*
X725984D03*
X729134D03*
X732283D03*
X713386Y273622D03*
X716535D03*
X719685D03*
X722835D03*
X725984D03*
X729134D03*
X732283D03*
X713386Y270472D03*
X716535D03*
X719685D03*
X722835D03*
X725984D03*
X729134D03*
X732283D03*
X713386Y267323D03*
X716535D03*
X719685D03*
X722835D03*
X725984D03*
X729134D03*
X732283D03*
X735433Y264173D03*
X738583D03*
X741732D03*
X744882D03*
X748031D03*
X751181D03*
X754331D03*
X757480D03*
X760630D03*
X763779D03*
X766929D03*
X770079D03*
X773228D03*
X776378D03*
X779527D03*
X782677D03*
X785827D03*
X788976D03*
X792126D03*
X795275D03*
X798425D03*
X735433Y261023D03*
X738583D03*
X741732D03*
X744882D03*
X748031D03*
X751181D03*
X754331D03*
X757480D03*
X760630D03*
X763779D03*
X766929D03*
X770079D03*
X773228D03*
X776378D03*
X779527D03*
X782677D03*
X785827D03*
X788976D03*
X792126D03*
X795275D03*
X798425D03*
X735433Y257874D03*
X738583D03*
X741732D03*
X744882D03*
X748031D03*
X751181D03*
X754331D03*
X757480D03*
X760630D03*
X763779D03*
X766929D03*
X770079D03*
X773228D03*
X776378D03*
X779527D03*
X782677D03*
X785827D03*
X788976D03*
X792126D03*
X795275D03*
X798425D03*
X735433Y254724D03*
X738583D03*
X741732D03*
X744882D03*
X748031D03*
X751181D03*
X754331D03*
X757480D03*
X760630D03*
X763779D03*
X766929D03*
X770079D03*
X773228D03*
X776378D03*
X779527D03*
X782677D03*
X785827D03*
X788976D03*
X792126D03*
X795275D03*
X798425D03*
X735433Y251575D03*
X738583D03*
X741732D03*
X744882D03*
X748031D03*
X751181D03*
X754331D03*
X757480D03*
X760630D03*
X763779D03*
X766929D03*
X770079D03*
X773228D03*
X776378D03*
X779527D03*
X782677D03*
X785827D03*
X788976D03*
X792126D03*
X795275D03*
X798425D03*
X735433Y248425D03*
X738583D03*
X741732D03*
X744882D03*
X748031D03*
X751181D03*
X754331D03*
X757480D03*
X760630D03*
X763779D03*
X766929D03*
X770079D03*
X773228D03*
X776378D03*
X779527D03*
X782677D03*
X785827D03*
X788976D03*
X792126D03*
X795275D03*
X798425D03*
X735433Y245275D03*
X738583D03*
X741732D03*
X744882D03*
X748031D03*
X751181D03*
X754331D03*
X757480D03*
X760630D03*
X763779D03*
X766929D03*
X770079D03*
X773228D03*
X776378D03*
X779527D03*
X782677D03*
X785827D03*
X788976D03*
X792126D03*
X795275D03*
X798425D03*
X735433Y242126D03*
X738583D03*
X741732D03*
X744882D03*
X748031D03*
X751181D03*
X754331D03*
X757480D03*
X760630D03*
X763779D03*
X766929D03*
X770079D03*
X773228D03*
X776378D03*
X779527D03*
X782677D03*
X785827D03*
X788976D03*
X792126D03*
X795275D03*
X798425D03*
X735433Y238976D03*
X738583D03*
X741732D03*
X744882D03*
X748031D03*
X751181D03*
X754331D03*
X757480D03*
X760630D03*
X763779D03*
X766929D03*
X770079D03*
X773228D03*
X776378D03*
X779527D03*
X782677D03*
X785827D03*
X788976D03*
X792126D03*
X795275D03*
X798425D03*
X735433Y235827D03*
X738583D03*
X741732D03*
X744882D03*
X748031D03*
X751181D03*
X754331D03*
X757480D03*
X760630D03*
X763779D03*
X766929D03*
X770079D03*
X773228D03*
X776378D03*
X779527D03*
X782677D03*
X785827D03*
X788976D03*
X792126D03*
X795275D03*
X798425D03*
X735433Y232677D03*
X738583D03*
X741732D03*
X744882D03*
X748031D03*
X751181D03*
X754331D03*
X757480D03*
X760630D03*
X763779D03*
X766929D03*
X770079D03*
X773228D03*
X776378D03*
X779527D03*
X782677D03*
X785827D03*
X788976D03*
X792126D03*
X795275D03*
X798425D03*
X735433Y229527D03*
X738583D03*
X741732D03*
X744882D03*
X748031D03*
X751181D03*
X754331D03*
X757480D03*
X760630D03*
X763779D03*
X766929D03*
X770079D03*
X773228D03*
X776378D03*
X779527D03*
X782677D03*
X785827D03*
X788976D03*
X792126D03*
X795275D03*
X798425D03*
X735433Y226378D03*
X738583D03*
X741732D03*
X744882D03*
X748031D03*
X751181D03*
X754331D03*
X757480D03*
X760630D03*
X763779D03*
X766929D03*
X770079D03*
X773228D03*
X776378D03*
X779527D03*
X782677D03*
X785827D03*
X788976D03*
X792126D03*
X795275D03*
X798425D03*
X735433Y223228D03*
X738583D03*
X741732D03*
X744882D03*
X748031D03*
X751181D03*
X754331D03*
X757480D03*
X760630D03*
X763779D03*
X766929D03*
X770079D03*
X773228D03*
X776378D03*
X779527D03*
X782677D03*
X785827D03*
X788976D03*
X792126D03*
X795275D03*
X798425D03*
X735433Y220079D03*
X738583D03*
X741732D03*
X744882D03*
X748031D03*
X751181D03*
X754331D03*
X757480D03*
X760630D03*
X763779D03*
X766929D03*
X770079D03*
X773228D03*
X776378D03*
X779527D03*
X782677D03*
X785827D03*
X788976D03*
X792126D03*
X795275D03*
X798425D03*
X735433Y216929D03*
X738583D03*
X741732D03*
X744882D03*
X748031D03*
X751181D03*
X754331D03*
X757480D03*
X760630D03*
X763779D03*
X766929D03*
X770079D03*
X773228D03*
X776378D03*
X779527D03*
X782677D03*
X785827D03*
X788976D03*
X792126D03*
X795275D03*
X735433Y213779D03*
X738583D03*
X741732D03*
X744882D03*
X748031D03*
X751181D03*
X754331D03*
X757480D03*
X760630D03*
X763779D03*
X766929D03*
X770079D03*
X773228D03*
X776378D03*
X779527D03*
X782677D03*
X785827D03*
X788976D03*
X792126D03*
X795275D03*
X735433Y210630D03*
X738583D03*
X741732D03*
X744882D03*
X748031D03*
X751181D03*
X754331D03*
X757480D03*
X760630D03*
X763779D03*
X766929D03*
X770079D03*
X773228D03*
X776378D03*
X779527D03*
X782677D03*
X785827D03*
X788976D03*
X792126D03*
X795275D03*
X735433Y301968D03*
X738583D03*
X741732D03*
X744882D03*
X748031D03*
X751181D03*
X754331D03*
X757480D03*
X760630D03*
X763779D03*
X766929D03*
X770079D03*
X773228D03*
X776378D03*
X779527D03*
X782677D03*
X785827D03*
X788976D03*
X792126D03*
X795275D03*
X735433Y298819D03*
X738583D03*
X741732D03*
X744882D03*
X748031D03*
X751181D03*
X754331D03*
X757480D03*
X760630D03*
X763779D03*
X766929D03*
X770079D03*
X773228D03*
X776378D03*
X779527D03*
X782677D03*
X785827D03*
X788976D03*
X792126D03*
X795275D03*
X735433Y295669D03*
X738583D03*
X741732D03*
X744882D03*
X748031D03*
X751181D03*
X754331D03*
X757480D03*
X760630D03*
X763779D03*
X766929D03*
X770079D03*
X773228D03*
X776378D03*
X779527D03*
X782677D03*
X785827D03*
X788976D03*
X792126D03*
X795275D03*
X735433Y292519D03*
X738583D03*
X741732D03*
X744882D03*
X748031D03*
X751181D03*
X754331D03*
X757480D03*
X760630D03*
X763779D03*
X766929D03*
X770079D03*
X773228D03*
X776378D03*
X779527D03*
X782677D03*
X785827D03*
X788976D03*
X792126D03*
X795275D03*
X798425D03*
X735433Y289370D03*
X738583D03*
X741732D03*
X744882D03*
X748031D03*
X751181D03*
X754331D03*
X757480D03*
X760630D03*
X763779D03*
X766929D03*
X770079D03*
X773228D03*
X776378D03*
X779527D03*
X782677D03*
X785827D03*
X788976D03*
X792126D03*
X795275D03*
X798425D03*
X735433Y286220D03*
X738583D03*
X741732D03*
X744882D03*
X748031D03*
X751181D03*
X754331D03*
X757480D03*
X760630D03*
X763779D03*
X766929D03*
X770079D03*
X773228D03*
X776378D03*
X779527D03*
X782677D03*
X785827D03*
X788976D03*
X792126D03*
X795275D03*
X798425D03*
X735433Y283071D03*
X738583D03*
X741732D03*
X744882D03*
X748031D03*
X751181D03*
X754331D03*
X757480D03*
X760630D03*
X763779D03*
X766929D03*
X770079D03*
X773228D03*
X776378D03*
X779527D03*
X782677D03*
X785827D03*
X788976D03*
X792126D03*
X795275D03*
X798425D03*
X735433Y279921D03*
X738583D03*
X741732D03*
X744882D03*
X748031D03*
X751181D03*
X754331D03*
X757480D03*
X760630D03*
X763779D03*
X766929D03*
X770079D03*
X773228D03*
X776378D03*
X779527D03*
X782677D03*
X785827D03*
X788976D03*
X792126D03*
X795275D03*
X798425D03*
X735433Y276771D03*
X738583D03*
X741732D03*
X744882D03*
X748031D03*
X751181D03*
X754331D03*
X757480D03*
X760630D03*
X763779D03*
X766929D03*
X770079D03*
X773228D03*
X776378D03*
X779527D03*
X782677D03*
X785827D03*
X788976D03*
X792126D03*
X795275D03*
X798425D03*
X735433Y273622D03*
X738583D03*
X741732D03*
X744882D03*
X748031D03*
X751181D03*
X754331D03*
X757480D03*
X760630D03*
X763779D03*
X766929D03*
X770079D03*
X773228D03*
X776378D03*
X779527D03*
X782677D03*
X785827D03*
X788976D03*
X792126D03*
X795275D03*
X798425D03*
X735433Y270472D03*
X738583D03*
X741732D03*
X744882D03*
X748031D03*
X751181D03*
X754331D03*
X757480D03*
X760630D03*
X763779D03*
X766929D03*
X770079D03*
X773228D03*
X776378D03*
X779527D03*
X782677D03*
X785827D03*
X788976D03*
X792126D03*
X795275D03*
X798425D03*
X735433Y267323D03*
X738583D03*
X741732D03*
X744882D03*
X748031D03*
X751181D03*
X754331D03*
X757480D03*
X760630D03*
X763779D03*
X766929D03*
X770079D03*
X773228D03*
X776378D03*
X779527D03*
X782677D03*
X785827D03*
X788976D03*
X792126D03*
X795275D03*
X798425D03*
X801575Y264173D03*
X804724D03*
X801575Y261023D03*
X804724D03*
X801575Y257874D03*
X804724D03*
X801575Y254724D03*
X804724D03*
X801575Y251575D03*
X804724D03*
X801575Y248425D03*
X804724D03*
X801575Y245275D03*
X804724D03*
X801575Y242126D03*
X804724D03*
X801575Y238976D03*
X804724D03*
X801575Y235827D03*
X804724D03*
X801575Y232677D03*
X804724D03*
X801575Y229527D03*
X804724D03*
X801575Y226378D03*
X804724D03*
X801575Y223228D03*
X804724D03*
X801575Y220079D03*
X804724D03*
X801575Y292519D03*
X804724D03*
X801575Y289370D03*
X804724D03*
X801575Y286220D03*
X804724D03*
X801575Y283071D03*
X804724D03*
X801575Y279921D03*
X804724D03*
X801575Y276771D03*
X804724D03*
X801575Y273622D03*
X804724D03*
X801575Y270472D03*
X804724D03*
X801575Y267323D03*
X804724D03*
G54D82*
X372000Y62500D03*
X344958Y107078D03*
G54D149*
G01X13215Y-125739D02*
X14089Y-124864D01*
X14744Y-123406D01*
X15181Y-121363D01*
X14744Y-119614D01*
X13871Y-118447D01*
X12342Y-117572D01*
X6447D01*
Y-135072D01*
X13652D01*
X15181Y-133906D01*
X16054Y-132155D01*
X16491Y-130114D01*
X16054Y-128072D01*
X14744Y-126322D01*
X13215Y-125739D01*
X6447D01*
G01X25912Y-135072D02*
Y-123406D01*
G01Y-125739D02*
X27004Y-124572D01*
X28096Y-123697D01*
X29624Y-123406D01*
X30715Y-123697D01*
X32026Y-124572D01*
G01X41884Y-140322D02*
X43194Y-140905D01*
X44941Y-140322D01*
X46032Y-139156D01*
X46906Y-137697D01*
X48215Y-133031D01*
X51054Y-123406D01*
G01X44067D02*
X48215Y-133031D01*
G01X67462Y-124864D02*
X65934Y-123697D01*
X64624Y-123406D01*
X62877Y-123989D01*
X61567Y-125155D01*
X60694Y-127197D01*
X60475Y-129239D01*
X60694Y-131281D01*
X61567Y-133031D01*
X62877Y-134489D01*
X64624Y-135072D01*
X66152Y-134489D01*
X67462Y-133322D01*
G01X78194Y-127197D02*
X85181D01*
X84526Y-125155D01*
X83434Y-123989D01*
X81906Y-123406D01*
X80377Y-123697D01*
X79067Y-124572D01*
X78194Y-126614D01*
X77757Y-128364D01*
Y-130114D01*
X78194Y-131864D01*
X79286Y-133614D01*
X80596Y-134780D01*
X82124Y-135072D01*
X83652Y-134489D01*
X85181Y-132739D01*
G01X121272Y-119031D02*
X119962Y-118155D01*
X118434Y-117572D01*
X116687D01*
X114722Y-118447D01*
X113194Y-119905D01*
X112102Y-121656D01*
X111229Y-124572D01*
X111010Y-127197D01*
X111447Y-129822D01*
X112102Y-131572D01*
X113412Y-133322D01*
X114941Y-134489D01*
X116469Y-135072D01*
X117997D01*
X119526Y-134489D01*
X120836Y-133614D01*
X121928Y-132448D01*
G01X137899Y-135072D02*
Y-123406D01*
G01Y-125447D02*
X137026Y-124281D01*
X135715Y-123697D01*
X134187Y-123406D01*
X132659Y-123989D01*
X131349Y-125155D01*
X130475Y-126905D01*
X130039Y-129239D01*
X130475Y-131572D01*
X131349Y-133322D01*
X132659Y-134489D01*
X134187Y-135072D01*
X135715Y-134780D01*
X137026Y-133906D01*
X137899Y-132739D01*
G01X147757Y-135072D02*
Y-123406D01*
G01Y-126322D02*
X148631Y-124864D01*
X149941Y-123697D01*
X151687Y-123406D01*
X153215Y-123697D01*
X154526Y-124864D01*
X155181Y-126905D01*
Y-135072D01*
G01X164384Y-140322D02*
X165694Y-140905D01*
X167441Y-140322D01*
X168532Y-139156D01*
X169406Y-137697D01*
X170715Y-133031D01*
X173554Y-123406D01*
G01X166567D02*
X170715Y-133031D01*
G01X186469Y-135072D02*
X185159Y-134780D01*
X183849Y-133614D01*
X182975Y-131572D01*
X182539Y-129239D01*
X182975Y-126905D01*
X183849Y-124864D01*
X185159Y-123697D01*
X186469Y-123406D01*
X187779Y-123697D01*
X189089Y-124864D01*
X189962Y-126905D01*
X190181Y-129239D01*
X189962Y-131572D01*
X189089Y-133614D01*
X187779Y-134780D01*
X186469Y-135072D01*
G01X200257D02*
Y-123406D01*
G01Y-126322D02*
X201131Y-124864D01*
X202441Y-123697D01*
X204187Y-123406D01*
X205715Y-123697D01*
X207026Y-124864D01*
X207681Y-126905D01*
Y-135072D01*
G01X236349Y-117572D02*
X241589D01*
G01X238969D02*
Y-135072D01*
G01X236349D02*
X241589D01*
G01X256469D02*
X254722Y-134780D01*
X253194Y-133614D01*
X251884Y-131864D01*
X251010Y-129822D01*
X250574Y-127489D01*
Y-125155D01*
X251010Y-122822D01*
X251884Y-120780D01*
X253194Y-119031D01*
X254722Y-117864D01*
X256469Y-117572D01*
X258215Y-117864D01*
X259744Y-119031D01*
X261054Y-120780D01*
X261928Y-122822D01*
X262364Y-125155D01*
Y-127489D01*
X261928Y-129822D01*
X261054Y-131864D01*
X259744Y-133614D01*
X258215Y-134780D01*
X256469Y-135072D01*
G01X268292D02*
Y-117572D01*
X273969Y-132155D01*
X279646Y-117572D01*
Y-135072D01*
G01X307877Y-140905D02*
X305694Y-137989D01*
X304602Y-135072D01*
Y-123406D01*
X305694Y-120489D01*
X307877Y-117572D01*
G01X321010Y-123406D02*
X323631Y-135072D01*
X326469Y-123406D01*
X329307Y-135072D01*
X331928Y-123406D01*
G01X340039Y-135655D02*
X347899Y-117572D01*
G01X376349D02*
X381589D01*
G01X378969D02*
Y-135072D01*
G01X376349D02*
X381589D01*
G01X396469D02*
X394722Y-134780D01*
X393194Y-133614D01*
X391884Y-131864D01*
X391010Y-129822D01*
X390574Y-127489D01*
Y-125155D01*
X391010Y-122822D01*
X391884Y-120780D01*
X393194Y-119031D01*
X394722Y-117864D01*
X396469Y-117572D01*
X398215Y-117864D01*
X399744Y-119031D01*
X401054Y-120780D01*
X401928Y-122822D01*
X402364Y-125155D01*
Y-127489D01*
X401928Y-129822D01*
X401054Y-131864D01*
X399744Y-133614D01*
X398215Y-134780D01*
X396469Y-135072D01*
G01X418772Y-119031D02*
X417462Y-118155D01*
X415934Y-117572D01*
X414187D01*
X412222Y-118447D01*
X410694Y-119905D01*
X409602Y-121656D01*
X408729Y-124572D01*
X408510Y-127197D01*
X408947Y-129822D01*
X409602Y-131572D01*
X410912Y-133322D01*
X412441Y-134489D01*
X413969Y-135072D01*
X415497D01*
X417026Y-134489D01*
X418336Y-133614D01*
X419428Y-132448D01*
G01X432561Y-140905D02*
X434744Y-137989D01*
X435836Y-135072D01*
Y-123406D01*
X434744Y-120489D01*
X432561Y-117572D01*
G01X180792Y-90072D02*
Y-72572D01*
X186469Y-87155D01*
X192146Y-72572D01*
Y-90072D01*
G01X203969D02*
X202659Y-89780D01*
X201349Y-88614D01*
X200475Y-86572D01*
X200039Y-84239D01*
X200475Y-81905D01*
X201349Y-79864D01*
X202659Y-78697D01*
X203969Y-78406D01*
X205279Y-78697D01*
X206589Y-79864D01*
X207462Y-81905D01*
X207681Y-84239D01*
X207462Y-86572D01*
X206589Y-88614D01*
X205279Y-89780D01*
X203969Y-90072D01*
G01X225399Y-72572D02*
Y-90072D01*
G01Y-87448D02*
X224526Y-88906D01*
X223215Y-89780D01*
X221687Y-90072D01*
X219941Y-89489D01*
X218631Y-88031D01*
X217757Y-86281D01*
X217539Y-84239D01*
X217757Y-82197D01*
X218631Y-80447D01*
X219941Y-78989D01*
X221687Y-78406D01*
X223215Y-78697D01*
X224307Y-79281D01*
X225399Y-80447D01*
G01X235694Y-82197D02*
X242681D01*
X242026Y-80155D01*
X240934Y-78989D01*
X239406Y-78406D01*
X237877Y-78697D01*
X236567Y-79572D01*
X235694Y-81614D01*
X235257Y-83364D01*
Y-85114D01*
X235694Y-86864D01*
X236786Y-88614D01*
X238096Y-89780D01*
X239624Y-90072D01*
X241152Y-89489D01*
X242681Y-87739D01*
G01X256469Y-90072D02*
Y-72572D01*
G01X490269Y-135072D02*
Y-117572D01*
X487649Y-121072D01*
G01Y-135072D02*
X492889D01*
G01X503621Y-127781D02*
X505149Y-125739D01*
X506459Y-124572D01*
X508206Y-123989D01*
X509734Y-124572D01*
X510826Y-125739D01*
X511699Y-127489D01*
X511917Y-129530D01*
X511699Y-131281D01*
X510826Y-133031D01*
X509515Y-134489D01*
X507987Y-135072D01*
X506241Y-134489D01*
X504712Y-132739D01*
X503839Y-130114D01*
X503621Y-127197D01*
X504057Y-123406D01*
X504712Y-121363D01*
X505804Y-119322D01*
X507332Y-117864D01*
X508861Y-117572D01*
X510389Y-118155D01*
X511481Y-119614D01*
G01X520466Y-131572D02*
X521775Y-133614D01*
X523522Y-134780D01*
X525487Y-135072D01*
X527234Y-134780D01*
X528981Y-133322D01*
X530072Y-131572D01*
X530291Y-129822D01*
X529854Y-127781D01*
X528326Y-126322D01*
X526797Y-125739D01*
X524832D01*
G01X526797D02*
X528107Y-124864D01*
X529199Y-123406D01*
X529636Y-121656D01*
X529199Y-119905D01*
X528107Y-118447D01*
X526142Y-117572D01*
X524177Y-117864D01*
X522212Y-119031D01*
G01X542769Y-135072D02*
Y-117572D01*
X540149Y-121072D01*
G01Y-135072D02*
X545389D01*
G01X560269D02*
X561797Y-134780D01*
X563544Y-133906D01*
X564636Y-132448D01*
X565072Y-130405D01*
X564636Y-128364D01*
X563326Y-126614D01*
X561361Y-125739D01*
X559177D01*
X557867Y-125155D01*
X556775Y-123697D01*
X556339Y-121656D01*
X556994Y-119614D01*
X558522Y-118155D01*
X560269Y-117572D01*
X562015Y-118155D01*
X563544Y-119614D01*
X564199Y-121656D01*
X563762Y-123697D01*
X562671Y-125155D01*
X561361Y-125739D01*
X559177D01*
X557212Y-126614D01*
X555902Y-128364D01*
X555466Y-130405D01*
X555902Y-132448D01*
X556994Y-133906D01*
X558741Y-134780D01*
X560269Y-135072D01*
G01X477152Y-90072D02*
Y-72572D01*
X482392D01*
X484139Y-73447D01*
X485449Y-75489D01*
X485886Y-77822D01*
X485449Y-80155D01*
X484357Y-81905D01*
X482392Y-82781D01*
X477152D01*
G01X503822Y-74031D02*
X502512Y-73155D01*
X500984Y-72572D01*
X499237D01*
X497272Y-73447D01*
X495744Y-74905D01*
X494652Y-76656D01*
X493779Y-79572D01*
X493560Y-82197D01*
X493997Y-84822D01*
X494652Y-86572D01*
X495962Y-88322D01*
X497491Y-89489D01*
X499019Y-90072D01*
X500547D01*
X502076Y-89489D01*
X503386Y-88614D01*
X504478Y-87448D01*
G01X518265Y-80739D02*
X519139Y-79864D01*
X519794Y-78406D01*
X520231Y-76363D01*
X519794Y-74614D01*
X518921Y-73447D01*
X517392Y-72572D01*
X511497D01*
Y-90072D01*
X518702D01*
X520231Y-88906D01*
X521104Y-87155D01*
X521541Y-85114D01*
X521104Y-83072D01*
X519794Y-81322D01*
X518265Y-80739D01*
X511497D01*
G01X527469Y-95905D02*
X540569D01*
G01X546497Y-90072D02*
Y-72572D01*
X556541Y-90072D01*
Y-72572D01*
G01X569019Y-90072D02*
X567272Y-89780D01*
X565744Y-88614D01*
X564434Y-86864D01*
X563560Y-84822D01*
X563124Y-82489D01*
Y-80155D01*
X563560Y-77822D01*
X564434Y-75780D01*
X565744Y-74031D01*
X567272Y-72864D01*
X569019Y-72572D01*
X570765Y-72864D01*
X572294Y-74031D01*
X573604Y-75780D01*
X574478Y-77822D01*
X574914Y-80155D01*
Y-82489D01*
X574478Y-84822D01*
X573604Y-86864D01*
X572294Y-88614D01*
X570765Y-89780D01*
X569019Y-90072D01*
G01X647421Y-120489D02*
X648731Y-118739D01*
X650259Y-117864D01*
X652006Y-117572D01*
X654189Y-118155D01*
X655717Y-119614D01*
X656154Y-121363D01*
X655936Y-123114D01*
X655062Y-124572D01*
X650696Y-127489D01*
X648731Y-129530D01*
X647421Y-132448D01*
X646984Y-135072D01*
X656154D01*
G01X619860Y-72572D02*
X625319Y-90072D01*
X630778Y-72572D01*
G01X647186Y-90072D02*
X638452D01*
Y-72572D01*
X647186D01*
G01X643692Y-81030D02*
X638452D01*
G01X655952Y-90072D02*
Y-72572D01*
X661411D01*
X663157Y-73447D01*
X664249Y-74614D01*
X664686Y-76947D01*
X664249Y-79281D01*
X662939Y-80739D01*
X661411Y-81614D01*
X655952D01*
G01X661411D02*
X664686Y-90072D01*
G01X677819Y-90655D02*
X677382Y-90364D01*
Y-89780D01*
X677819Y-89489D01*
X678256Y-89780D01*
Y-90364D01*
X677819Y-90655D01*
G01X779652Y-117572D02*
Y-135072D01*
X788386D01*
G01X801519D02*
Y-117572D01*
X798899Y-121072D01*
G01Y-135072D02*
X804139D01*
G01X753402Y-72572D02*
Y-90072D01*
X762136D01*
G01X779199D02*
Y-78406D01*
G01Y-80447D02*
X778326Y-79281D01*
X777015Y-78697D01*
X775487Y-78406D01*
X773959Y-78989D01*
X772649Y-80155D01*
X771775Y-81905D01*
X771339Y-84239D01*
X771775Y-86572D01*
X772649Y-88322D01*
X773959Y-89489D01*
X775487Y-90072D01*
X777015Y-89780D01*
X778326Y-88906D01*
X779199Y-87739D01*
G01X788184Y-95322D02*
X789494Y-95905D01*
X791241Y-95322D01*
X792332Y-94156D01*
X793206Y-92697D01*
X794515Y-88031D01*
X797354Y-78406D01*
G01X790367D02*
X794515Y-88031D01*
G01X806994Y-82197D02*
X813981D01*
X813326Y-80155D01*
X812234Y-78989D01*
X810706Y-78406D01*
X809177Y-78697D01*
X807867Y-79572D01*
X806994Y-81614D01*
X806557Y-83364D01*
Y-85114D01*
X806994Y-86864D01*
X808086Y-88614D01*
X809396Y-89780D01*
X810924Y-90072D01*
X812452Y-89489D01*
X813981Y-87739D01*
G01X824712Y-90072D02*
Y-78406D01*
G01Y-80739D02*
X825804Y-79572D01*
X826896Y-78697D01*
X828424Y-78406D01*
X829515Y-78697D01*
X830826Y-79572D01*
G01X917819Y-135072D02*
X916072Y-134780D01*
X914544Y-133614D01*
X913234Y-131864D01*
X912360Y-129822D01*
X911924Y-127489D01*
Y-125155D01*
X912360Y-122822D01*
X913234Y-120780D01*
X914544Y-119031D01*
X916072Y-117864D01*
X917819Y-117572D01*
X919565Y-117864D01*
X921094Y-119031D01*
X922404Y-120780D01*
X923278Y-122822D01*
X923714Y-125155D01*
Y-127489D01*
X923278Y-129822D01*
X922404Y-131864D01*
X921094Y-133614D01*
X919565Y-134780D01*
X917819Y-135072D01*
G01X919565Y-130405D02*
X922186Y-135072D01*
G01X930516Y-117572D02*
Y-130114D01*
X931389Y-132739D01*
X933136Y-134489D01*
X935319Y-135072D01*
X937502Y-134489D01*
X939249Y-132739D01*
X940122Y-130114D01*
Y-117572D01*
G01X950199D02*
X955439D01*
G01X952819D02*
Y-135072D01*
G01X950199D02*
X955439D01*
G01X965297D02*
Y-117572D01*
X975341Y-135072D01*
Y-117572D01*
G01X992622Y-119031D02*
X991312Y-118155D01*
X989784Y-117572D01*
X988037D01*
X986072Y-118447D01*
X984544Y-119905D01*
X983452Y-121656D01*
X982579Y-124572D01*
X982360Y-127197D01*
X982797Y-129822D01*
X983452Y-131572D01*
X984762Y-133322D01*
X986291Y-134489D01*
X987819Y-135072D01*
X989347D01*
X990876Y-134489D01*
X992186Y-133614D01*
X993278Y-132448D01*
G01X1005319Y-135072D02*
Y-127197D01*
X1000952Y-117572D01*
G01X1009686D02*
X1005319Y-127197D01*
G01X895516Y-90072D02*
Y-72572D01*
X899882D01*
X901629Y-73447D01*
X902939Y-74614D01*
X904031Y-76363D01*
X904904Y-78406D01*
X905122Y-81322D01*
X904904Y-84239D01*
X904031Y-86281D01*
X902939Y-88031D01*
X901629Y-89197D01*
X899882Y-90072D01*
X895516D01*
G01X914544Y-82197D02*
X921531D01*
X920876Y-80155D01*
X919784Y-78989D01*
X918256Y-78406D01*
X916727Y-78697D01*
X915417Y-79572D01*
X914544Y-81614D01*
X914107Y-83364D01*
Y-85114D01*
X914544Y-86864D01*
X915636Y-88614D01*
X916946Y-89780D01*
X918474Y-90072D01*
X920002Y-89489D01*
X921531Y-87739D01*
G01X932044Y-88031D02*
X933136Y-89197D01*
X934664Y-90072D01*
X935974D01*
X937284Y-89489D01*
X938157Y-88614D01*
X938594Y-87448D01*
X938376Y-85697D01*
X937502Y-84822D01*
X933572Y-83072D01*
X932699Y-81030D01*
X933136Y-79572D01*
X934009Y-78697D01*
X935319Y-78406D01*
X936629Y-78697D01*
X937939Y-79572D01*
G01X952819Y-78406D02*
Y-90072D01*
G01Y-73739D02*
X952382Y-73447D01*
Y-72864D01*
X952819Y-72572D01*
X953256Y-72864D01*
Y-73447D01*
X952819Y-73739D01*
G01X967262Y-94447D02*
X968791Y-95614D01*
X970537Y-95905D01*
X972065Y-95614D01*
X973376Y-94156D01*
X974249Y-92114D01*
Y-78406D01*
G01Y-80739D02*
X973376Y-79572D01*
X972065Y-78697D01*
X970537Y-78406D01*
X968791Y-78989D01*
X967699Y-80155D01*
X966825Y-82197D01*
X966389Y-84239D01*
X966607Y-85989D01*
X967481Y-88031D01*
X968791Y-89489D01*
X970537Y-90072D01*
X971847Y-89780D01*
X973376Y-88614D01*
X974249Y-87448D01*
G01X984107Y-90072D02*
Y-78406D01*
G01Y-81322D02*
X984981Y-79864D01*
X986291Y-78697D01*
X988037Y-78406D01*
X989565Y-78697D01*
X990876Y-79864D01*
X991531Y-81905D01*
Y-90072D01*
G01X1002044Y-82197D02*
X1009031D01*
X1008376Y-80155D01*
X1007284Y-78989D01*
X1005756Y-78406D01*
X1004227Y-78697D01*
X1002917Y-79572D01*
X1002044Y-81614D01*
X1001607Y-83364D01*
Y-85114D01*
X1002044Y-86864D01*
X1003136Y-88614D01*
X1004446Y-89780D01*
X1005974Y-90072D01*
X1007502Y-89489D01*
X1009031Y-87739D01*
G01X1019762Y-90072D02*
Y-78406D01*
G01Y-80739D02*
X1020854Y-79572D01*
X1021946Y-78697D01*
X1023474Y-78406D01*
X1024565Y-78697D01*
X1025876Y-79572D01*
G01X1066519Y-117572D02*
X1064772Y-118155D01*
X1063462Y-119614D01*
X1062589Y-121363D01*
X1061934Y-123697D01*
X1061716Y-126322D01*
X1061934Y-128947D01*
X1062589Y-131281D01*
X1063462Y-133031D01*
X1064772Y-134489D01*
X1066519Y-135072D01*
X1068265Y-134489D01*
X1069576Y-133031D01*
X1070449Y-131281D01*
X1071104Y-128947D01*
X1071322Y-126322D01*
X1071104Y-123697D01*
X1070449Y-121363D01*
X1069576Y-119614D01*
X1068265Y-118155D01*
X1066519Y-117572D01*
G01X1084019Y-135072D02*
X1085547Y-134780D01*
X1087294Y-133906D01*
X1088386Y-132448D01*
X1088822Y-130405D01*
X1088386Y-128364D01*
X1087076Y-126614D01*
X1085111Y-125739D01*
X1082927D01*
X1081617Y-125155D01*
X1080525Y-123697D01*
X1080089Y-121656D01*
X1080744Y-119614D01*
X1082272Y-118155D01*
X1084019Y-117572D01*
X1085765Y-118155D01*
X1087294Y-119614D01*
X1087949Y-121656D01*
X1087512Y-123697D01*
X1086421Y-125155D01*
X1085111Y-125739D01*
X1082927D01*
X1080962Y-126614D01*
X1079652Y-128364D01*
X1079216Y-130405D01*
X1079652Y-132448D01*
X1080744Y-133906D01*
X1082491Y-134780D01*
X1084019Y-135072D01*
G01X1097589Y-135655D02*
X1105449Y-117572D01*
G01X1119019D02*
X1117272Y-118155D01*
X1115962Y-119614D01*
X1115089Y-121363D01*
X1114434Y-123697D01*
X1114216Y-126322D01*
X1114434Y-128947D01*
X1115089Y-131281D01*
X1115962Y-133031D01*
X1117272Y-134489D01*
X1119019Y-135072D01*
X1120765Y-134489D01*
X1122076Y-133031D01*
X1122949Y-131281D01*
X1123604Y-128947D01*
X1123822Y-126322D01*
X1123604Y-123697D01*
X1122949Y-121363D01*
X1122076Y-119614D01*
X1120765Y-118155D01*
X1119019Y-117572D01*
G01X1136082Y-135072D02*
X1136519Y-131281D01*
X1137174Y-128072D01*
X1138047Y-125155D01*
X1139139Y-121947D01*
X1140886Y-117572D01*
X1132152D01*
G01X1150089Y-135655D02*
X1157949Y-117572D01*
G01X1167371Y-120489D02*
X1168681Y-118739D01*
X1170209Y-117864D01*
X1171956Y-117572D01*
X1174139Y-118155D01*
X1175667Y-119614D01*
X1176104Y-121363D01*
X1175886Y-123114D01*
X1175012Y-124572D01*
X1170646Y-127489D01*
X1168681Y-129530D01*
X1167371Y-132448D01*
X1166934Y-135072D01*
X1176104D01*
G01X1189019Y-117572D02*
X1187272Y-118155D01*
X1185962Y-119614D01*
X1185089Y-121363D01*
X1184434Y-123697D01*
X1184216Y-126322D01*
X1184434Y-128947D01*
X1185089Y-131281D01*
X1185962Y-133031D01*
X1187272Y-134489D01*
X1189019Y-135072D01*
X1190765Y-134489D01*
X1192076Y-133031D01*
X1192949Y-131281D01*
X1193604Y-128947D01*
X1193822Y-126322D01*
X1193604Y-123697D01*
X1192949Y-121363D01*
X1192076Y-119614D01*
X1190765Y-118155D01*
X1189019Y-117572D01*
G01X1206519Y-135072D02*
Y-117572D01*
X1203899Y-121072D01*
G01Y-135072D02*
X1209139D01*
G01X1223582D02*
X1224019Y-131281D01*
X1224674Y-128072D01*
X1225547Y-125155D01*
X1226639Y-121947D01*
X1228386Y-117572D01*
X1219652D01*
G01X1114216Y-90072D02*
Y-72572D01*
X1118582D01*
X1120329Y-73447D01*
X1121639Y-74614D01*
X1122731Y-76363D01*
X1123604Y-78406D01*
X1123822Y-81322D01*
X1123604Y-84239D01*
X1122731Y-86281D01*
X1121639Y-88031D01*
X1120329Y-89197D01*
X1118582Y-90072D01*
X1114216D01*
G01X1140449D02*
Y-78406D01*
G01Y-80447D02*
X1139576Y-79281D01*
X1138265Y-78697D01*
X1136737Y-78406D01*
X1135209Y-78989D01*
X1133899Y-80155D01*
X1133025Y-81905D01*
X1132589Y-84239D01*
X1133025Y-86572D01*
X1133899Y-88322D01*
X1135209Y-89489D01*
X1136737Y-90072D01*
X1138265Y-89780D01*
X1139576Y-88906D01*
X1140449Y-87739D01*
G01X1154019Y-72572D02*
Y-90072D01*
G01X1150962Y-78406D02*
X1157076D01*
G01X1168244Y-82197D02*
X1175231D01*
X1174576Y-80155D01*
X1173484Y-78989D01*
X1171956Y-78406D01*
X1170427Y-78697D01*
X1169117Y-79572D01*
X1168244Y-81614D01*
X1167807Y-83364D01*
Y-85114D01*
X1168244Y-86864D01*
X1169336Y-88614D01*
X1170646Y-89780D01*
X1172174Y-90072D01*
X1173702Y-89489D01*
X1175231Y-87739D01*
G54D83*
X372000Y65500D03*
X344958Y110078D03*
G54D47*
X134700Y697350D03*
G54D38*
X65714Y665850D03*
X306300Y638600D03*
X295634Y710070D03*
X810214Y499850D03*
G54D92*
X369273Y645871D03*
X360049D03*
Y651827D03*
X369273D03*
G54D74*
X315252Y546325D03*
Y544355D03*
Y542385D03*
Y540415D03*
X306052D03*
Y542385D03*
Y544355D03*
Y546325D03*
X377739Y513804D03*
Y511839D03*
Y509869D03*
Y507899D03*
Y505934D03*
X361439D03*
Y507899D03*
Y509869D03*
Y511839D03*
Y513804D03*
G54D29*
X50050Y529400D03*
X55895Y643491D03*
X73265Y647355D03*
X49300Y656600D03*
X34300Y677500D03*
X76264Y685964D03*
X46043Y679557D03*
X88900Y498700D03*
X103800Y570500D03*
X126870Y598031D03*
X139959Y606009D03*
X139971Y614874D03*
X112850Y641488D03*
X128793Y613483D03*
X139728Y596666D03*
X83450Y646620D03*
X144550Y618316D03*
X123534Y593743D03*
X117000Y597000D03*
X115006Y625751D03*
X139679Y601454D03*
X144000Y645600D03*
X127900Y643420D03*
X134700Y643441D03*
X127597Y693231D03*
X117767Y702633D03*
X121501Y699049D03*
X106400Y722900D03*
X138653Y739871D03*
X144249Y733200D03*
X199755Y524755D03*
X194803Y525639D03*
X187000Y524214D03*
X188584Y528105D03*
X177017Y526942D03*
X172800Y524100D03*
X170200Y527400D03*
X182000Y527362D03*
X162800Y527600D03*
X153812Y526926D03*
X158100Y524100D03*
X210000Y510000D03*
X204752Y524566D03*
X145100Y539800D03*
X145012Y544801D03*
X145100Y549900D03*
X205000Y614500D03*
X194200Y613700D03*
X189185Y617400D03*
X185085Y613700D03*
X182200Y617100D03*
X178800Y614100D03*
X175040Y616035D03*
X163300Y629800D03*
X197315Y617778D03*
X201449Y619094D03*
X149250Y618050D03*
X153901Y617796D03*
X158898Y617993D03*
X160200Y639600D03*
X156238Y643866D03*
X160249Y699165D03*
X144662Y697593D03*
X269600Y523350D03*
X225300Y527900D03*
X231800Y522500D03*
X221800Y523700D03*
X221187Y516937D03*
X213487Y524273D03*
X272723Y540752D03*
X230940Y565901D03*
X236700Y562800D03*
X235339Y568279D03*
X235721Y575076D03*
X236210Y584419D03*
X232763Y579124D03*
X231200Y559800D03*
X267200Y548200D03*
X259800Y528926D03*
X257161Y559865D03*
X250700Y530500D03*
X241300Y585000D03*
X231204Y529404D03*
X267200Y576400D03*
X240800Y528500D03*
X252590Y538010D03*
X211600Y614400D03*
X216000Y622450D03*
X223593Y634091D03*
X220400Y654600D03*
X214500Y626500D03*
X220614Y616544D03*
X233300Y618300D03*
X238000Y617896D03*
X237000Y597400D03*
X275500Y652348D03*
X240300Y613737D03*
X238950Y651600D03*
X252492Y643414D03*
X264683Y638810D03*
X273467Y657050D03*
X248600Y699300D03*
X256900Y699715D03*
X275349Y723500D03*
X256666Y716225D03*
X271240Y680097D03*
X267350Y710224D03*
X247400Y679150D03*
X221987Y728528D03*
X222306Y737851D03*
X338882Y248674D03*
X340500Y236600D03*
X338982Y243274D03*
X338751Y268585D03*
X339182Y273077D03*
X289500Y451900D03*
X337600Y494968D03*
X318778Y510778D03*
X301620Y515600D03*
X287615Y524997D03*
X340800Y504200D03*
X287271Y545971D03*
X287200Y553300D03*
X306364Y574464D03*
X307519Y584195D03*
X307385Y559544D03*
X307187Y566066D03*
X303091Y568720D03*
X301365Y573221D03*
X298308Y530131D03*
X281158Y538858D03*
X309417Y589500D03*
X323956Y539616D03*
X299294Y542868D03*
X322511Y544355D03*
X320031Y535663D03*
X301216Y535004D03*
X299200Y597400D03*
X290399Y656015D03*
X289917Y649778D03*
X301700Y608000D03*
X314390Y620830D03*
X285988Y637449D03*
X281300Y670200D03*
X282600Y674600D03*
X286500Y693500D03*
X309090Y690532D03*
X276325Y705863D03*
X316000Y671850D03*
X339731Y682730D03*
X301054Y666724D03*
X340583Y670807D03*
X283080Y730387D03*
X374014Y188823D03*
X353762Y181744D03*
X344388Y179571D03*
X362727Y192756D03*
X352017Y263432D03*
X383140Y367158D03*
X360446Y358846D03*
X361176Y379610D03*
X354850Y376362D03*
X369300Y362600D03*
X383900Y422100D03*
X390999Y461382D03*
X352700Y498400D03*
X360400Y470400D03*
X395928Y482925D03*
X377644Y491967D03*
X343000Y492100D03*
X344700Y522600D03*
X376700Y480300D03*
X368543Y479991D03*
X360374Y486117D03*
X352490Y515908D03*
X387561Y540889D03*
X355400Y593400D03*
X372700Y593600D03*
X379628Y589070D03*
X375771Y590734D03*
X383622Y590370D03*
X384746Y547941D03*
X349700Y577400D03*
X386835Y563988D03*
X351030Y536681D03*
X345443Y531460D03*
X365270Y580800D03*
X349334Y557789D03*
X349005Y549206D03*
X385845Y614925D03*
X383127Y595147D03*
X383271Y605000D03*
X388300Y632700D03*
X383168Y626894D03*
X346485Y676801D03*
X383885Y684055D03*
X381888Y678912D03*
X381377Y672923D03*
X380900Y692940D03*
X451500Y28000D03*
X451800Y23000D03*
X467800Y58000D03*
X448859Y42351D03*
X452293Y50940D03*
X460024Y18801D03*
X450900Y33300D03*
X458662Y53326D03*
X470599Y71247D03*
X469653Y88700D03*
X445163Y102450D03*
X456430Y87000D03*
X516600Y49650D03*
X517825Y54994D03*
X521155Y19621D03*
X497990Y54540D03*
X512542Y19091D03*
X473100Y58000D03*
X483235Y36335D03*
X484414Y26637D03*
X476305Y53965D03*
X484965Y63428D03*
X485104Y21491D03*
X481831Y17711D03*
X498150Y26850D03*
X489730Y77724D03*
X494171Y73533D03*
X475310Y89843D03*
X565100Y60400D03*
X551200Y47300D03*
X564100Y44203D03*
X581476Y43046D03*
X549650Y67500D03*
X582090Y58780D03*
X574759Y68489D03*
X555327Y81900D03*
X588676Y373300D03*
X602860Y522543D03*
X640600Y151600D03*
X665500Y201900D03*
X607400Y299100D03*
X657500Y281500D03*
X648000Y281300D03*
X639878Y348571D03*
X618900Y338200D03*
X620139Y380400D03*
X620111Y367921D03*
X608500Y343300D03*
X612466Y368519D03*
X653449Y360181D03*
X632220Y393520D03*
X640960Y377294D03*
X643200Y366300D03*
X603597Y335950D03*
X614022Y382345D03*
X626262Y377540D03*
X655800Y400550D03*
X640891Y414908D03*
X632180Y401800D03*
X635480Y526130D03*
X621108Y520852D03*
X640160Y517269D03*
X647359Y560063D03*
X607676Y540800D03*
X625398Y550500D03*
X634384Y550513D03*
X623327Y559229D03*
X603831Y548331D03*
X639500Y540500D03*
X639300Y532700D03*
X641380Y693090D03*
X647413Y697494D03*
X720878Y180410D03*
X717700Y196400D03*
X710403Y197200D03*
X706357Y180801D03*
X690000Y249500D03*
X690094Y243050D03*
X699145Y258217D03*
X704000Y244800D03*
X694500Y254517D03*
X704508Y233964D03*
X703452Y200958D03*
X694150Y267984D03*
X693668Y278378D03*
X689809Y290474D03*
X703130Y268891D03*
X693300Y273000D03*
X718427Y358980D03*
X709008Y354239D03*
X728038Y336182D03*
X733036Y351439D03*
X675130Y381713D03*
X714200Y445400D03*
X703617Y431443D03*
X683048Y443658D03*
X726211Y483619D03*
X729365Y488535D03*
X696100Y499100D03*
X696500Y465373D03*
X676418Y475383D03*
X681639Y499750D03*
X675300Y499000D03*
X697095Y480132D03*
X729346Y573866D03*
X718551Y555953D03*
X669294Y579571D03*
X706600Y546800D03*
X714777Y561129D03*
X717314Y587242D03*
X714978Y547961D03*
X693500Y554300D03*
X693484Y654328D03*
X733872Y629500D03*
X711081Y595223D03*
X723415Y621166D03*
X720300Y615300D03*
X693405Y676551D03*
X681740Y705064D03*
X752331Y61071D03*
X777666Y43729D03*
X786200Y60535D03*
X766542Y44076D03*
X761600Y68300D03*
X797500Y48500D03*
X783350Y80050D03*
X757100Y113000D03*
X766260Y92788D03*
X776200Y93050D03*
X789000Y100400D03*
X776300Y110100D03*
X778760Y123150D03*
X745300Y196300D03*
X765800Y196847D03*
X746891Y200751D03*
X755729Y201712D03*
X761780Y201451D03*
X741500Y201840D03*
X782693Y431308D03*
X744806Y495350D03*
X758100Y478184D03*
X744018Y516886D03*
X754462Y496762D03*
X771200Y492800D03*
X761200Y511300D03*
X739900Y505700D03*
X758901Y488563D03*
X753519Y508069D03*
X767300Y473700D03*
X795922Y518640D03*
X790200Y514000D03*
X793700Y493400D03*
X784500Y518694D03*
X736394Y593579D03*
X754775Y538079D03*
X790459Y538770D03*
X777100Y531200D03*
X814900Y61800D03*
X809000Y62000D03*
X824200Y48300D03*
X836400Y61300D03*
X858820Y232979D03*
X827988Y238779D03*
X851700Y382900D03*
X857664Y395138D03*
X822958Y393800D03*
X843619Y378326D03*
X856463Y399163D03*
X822900Y399400D03*
X823256Y406365D03*
X810341Y398947D03*
X813974Y404934D03*
X831489Y510582D03*
X800389Y482153D03*
X819036Y481398D03*
X892850Y313349D03*
X881200Y316000D03*
X887703Y300225D03*
X867602Y368048D03*
G54D65*
X230315Y679921D03*
G54D56*
X159149Y687715D03*
X440100Y52457D03*
Y42657D03*
Y47557D03*
X635460Y521543D03*
X709000Y558300D03*
X826824Y42000D03*
X800824D03*
G54D57*
X197087Y679921D03*
G54D48*
X135019Y714845D03*
G54D66*
X258800Y669800D03*
X262400D03*
X662100Y429900D03*
X665700D03*
X662100Y409400D03*
X665700D03*
X662100Y413500D03*
X665700D03*
X662100Y417600D03*
X665700D03*
X662100Y421700D03*
X665700D03*
X662100Y425800D03*
X665700D03*
G54D39*
X55971Y660732D03*
Y663291D03*
Y665850D03*
Y668409D03*
Y670968D03*
X75457D03*
Y668409D03*
Y665850D03*
Y663291D03*
Y660732D03*
X296557Y633482D03*
Y636041D03*
Y638600D03*
Y641159D03*
Y643718D03*
X316043D03*
Y641159D03*
Y638600D03*
Y636041D03*
Y633482D03*
X285891Y704952D03*
Y707511D03*
Y710070D03*
Y712629D03*
Y715188D03*
X305377D03*
Y712629D03*
Y710070D03*
Y707511D03*
Y704952D03*
X800471Y494732D03*
Y497291D03*
Y499850D03*
Y502409D03*
Y504968D03*
X819957D03*
Y502409D03*
Y499850D03*
Y497291D03*
Y494732D03*
G54D93*
X357290Y624270D03*
X373038D03*
Y600970D03*
X357290D03*
G54D84*
X374800Y111000D03*
Y116000D03*
Y121000D03*
X652500Y499600D03*
X651200Y545100D03*
X649900Y540300D03*
X713800Y619000D03*
X722100Y603700D03*
X772555Y39735D03*
X768300Y483800D03*
G54D75*
X327561Y656480D03*
X335311D03*
X331436Y663980D03*
X343006Y656555D03*
X350756D03*
X346881Y664055D03*
X555625Y68750D03*
X563375D03*
X559500Y76250D03*
X642345Y391494D03*
X650095D03*
X646220Y398994D03*
X783125Y66750D03*
X790875D03*
X786750Y93550D03*
X782875Y86050D03*
X790625D03*
X787000Y74250D03*
X785600Y117600D03*
X781725Y110100D03*
X789475D03*
X897344Y306791D03*
X893469Y299291D03*
X901219D03*
G54D76*
X299900Y657300D03*
Y660900D03*
G54D58*
X207795Y670886D03*
X203858D03*
X209764Y688956D03*
X205827D03*
X223544Y670886D03*
X219607D03*
X215670D03*
X211732D03*
X221575Y688956D03*
X217638D03*
X213701D03*
G54D67*
X243199Y718747D03*
X232199D03*
X243199Y737947D03*
X232199D03*
X243199Y728347D03*
X232199D03*
X766680Y119860D03*
X755680D03*
G54D49*
X125376Y705002D03*
Y706971D03*
Y708939D03*
Y710908D03*
Y712876D03*
Y714845D03*
Y716814D03*
Y718782D03*
Y720751D03*
Y722719D03*
X144662D03*
Y720751D03*
Y718782D03*
Y716814D03*
Y714845D03*
Y712876D03*
Y710908D03*
Y708939D03*
Y706971D03*
Y705002D03*
X125376Y724688D03*
X144662D03*
G54D94*
X376814Y620494D03*
Y604746D03*
X353514D03*
Y620494D03*
G54D85*
X369200Y111000D03*
Y116000D03*
Y121000D03*
X646900Y499600D03*
X645600Y545100D03*
X644300Y540300D03*
X708200Y619000D03*
X716500Y603700D03*
X766955Y39735D03*
X762700Y483800D03*
G54D59*
X197920Y712091D03*
Y736891D03*
X367762Y131001D03*
Y155801D03*
X833400Y451600D03*
Y426800D03*
X808200Y451600D03*
Y426800D03*
G54D68*
X274200Y663600D03*
X283200D03*
G54D86*
X360500Y112960D03*
Y116700D03*
Y120440D03*
X351500D03*
Y112960D03*
X369500Y702460D03*
Y706200D03*
Y709940D03*
X360500D03*
Y702460D03*
G54D95*
X359258Y623920D03*
X361227D03*
X363195D03*
X365164D03*
X367133D03*
X369101D03*
X371070D03*
Y601320D03*
X369101D03*
X367133D03*
X365164D03*
X363195D03*
X361227D03*
X359258D03*
G54D77*
X346457Y66850D03*
Y57007D03*
X353543Y70787D03*
Y62913D03*
Y55039D03*
X346457Y74724D03*
Y84567D03*
X353543Y86535D03*
Y78661D03*
G54D78*
X390527Y67190D03*
X386727D03*
X390527Y73790D03*
X386727D03*
G54D96*
X376464Y618526D03*
Y616557D03*
Y614589D03*
Y612620D03*
Y610651D03*
Y608683D03*
Y606714D03*
X353864D03*
Y608683D03*
Y610651D03*
Y612620D03*
Y614589D03*
Y616557D03*
Y618526D03*
G54D87*
X372000Y71900D03*
G54D69*
X339331Y49803D03*
X360669Y91929D03*
G54D97*
X365164Y612620D03*
G54D88*
X356611Y200364D03*
X351611D03*
X346611D03*
X341611D03*
Y220364D03*
X346611D03*
X351611D03*
X356611D03*
G54D79*
X371768Y53823D03*
Y49223D03*
X371594Y84695D03*
Y80095D03*
G54D89*
X368412Y232724D03*
X354572D03*
G54D98*
X461110Y45450D03*
Y25350D03*
X474890Y45450D03*
Y25350D03*
G54D99*
X463079Y45150D03*
X465047D03*
X467016D03*
X468984D03*
X470953D03*
Y25650D03*
X468984D03*
X467016D03*
X465047D03*
X463079D03*
X472921Y45150D03*
Y25650D03*
M02*
